(kicad_pcb
	(version 20260206)
	(generator "pcbnew")
	(generator_version "10.0")
	(general
		(thickness 0.77098)
		(legacy_teardrops no)
	)
	(paper "A4")
	(layers
		(0 "F.Cu" signal "L01-Top Layer")
		(4 "In1.Cu" signal "L02-Inner Layer")
		(6 "In2.Cu" signal "L03-Inner Layer")
		(2 "B.Cu" signal "L04-Bottom Layer")
		(9 "F.Adhes" user "F.Adhesive")
		(11 "B.Adhes" user "B.Adhesive")
		(13 "F.Paste" user "Top Paste")
		(15 "B.Paste" user "Bottom Paste")
		(5 "F.SilkS" user "Top Overlay")
		(7 "B.SilkS" user "Bottom Overlay")
		(1 "F.Mask" user "Top Solder")
		(3 "B.Mask" user "Bottom Solder")
		(17 "Dwgs.User" user "User.Drawings")
		(19 "Cmts.User" user "User.Comments")
		(21 "Eco1.User" user "User.Eco1")
		(23 "Eco2.User" user "User.Eco2")
		(25 "Edge.Cuts" user)
		(27 "Margin" user)
		(31 "F.CrtYd" user "Top Courtyard")
		(29 "B.CrtYd" user "Bottom Courtyard")
		(35 "F.Fab" user "Top Component Outline")
		(33 "B.Fab" user "Bottom Component Outline 2")
	)
	(setup
		(pad_to_mask_clearance 0.05)
		(allow_soldermask_bridges_in_footprints no)
		(tenting
			(front yes)
			(back yes)
		)
		(covering
			(front no)
			(back no)
		)
		(plugging
			(front no)
			(back no)
		)
		(capping no)
		(filling no)
		(aux_axis_origin 7.100105 311.8036)
		(grid_origin 7.100105 311.8036)
		(pcbplotparams
			(layerselection 0x00000000_00000000_55555555_5755f5ff)
			(plot_on_all_layers_selection 0x00000000_00000000_00000000_00000000)
			(disableapertmacros no)
			(usegerberextensions no)
			(usegerberattributes yes)
			(usegerberadvancedattributes yes)
			(creategerberjobfile yes)
			(dashed_line_dash_ratio 12)
			(dashed_line_gap_ratio 3)
			(svgprecision 4)
			(plotframeref no)
			(mode 1)
			(useauxorigin no)
			(pdf_front_fp_property_popups yes)
			(pdf_back_fp_property_popups yes)
			(pdf_metadata yes)
			(pdf_single_document no)
			(dxfpolygonmode yes)
			(dxfimperialunits yes)
			(dxfusepcbnewfont yes)
			(psnegative no)
			(psa4output no)
			(plot_black_and_white yes)
			(sketchpadsonfab no)
			(plotpadnumbers no)
			(hidednponfab no)
			(sketchdnponfab yes)
			(crossoutdnponfab yes)
			(subtractmaskfromsilk no)
			(outputformat 1)
			(mirror no)
			(drillshape 1)
			(scaleselection 1)
			(outputdirectory "")
		)
	)
	(footprint "Vault:FP-0402-L_1_0_0_05-W_0_5-IPC_B"
		(layer "F.Cu")
		(at 141.501105 91.0036 -90)
		(property "Reference" "C11"
			(at -2.29999 5.307371 270)
			(unlocked yes)
			(layer "F.SilkS")
			(effects
				(font
					(face "Arial")
					(size 0.96012 0.96012)
					(thickness 0.254)
				)
			)
		)
		(property "Value" "100nF"
			(at 2.70399 2.099971 270)
			(unlocked yes)
			(layer "F.SilkS")
			(hide yes)
			(effects
				(font
					(face "Arial")
					(size 0.96012 0.96012)
					(thickness 0.254)
				)
			)
		)
		(sheetname "02-Antenna_Supervisor")
		(sheetfile "02-Antenna_Supervisor.kicad_sch")
		(duplicate_pad_numbers_are_jumpers no)
		(fp_line
			(start -0.88624 0.43624)
			(end -0.88624 -0.43624)
			(stroke
				(width 0.2)
				(type solid)
			)
			(layer "F.CrtYd")
		)
		(fp_line
			(start 0.88624 0.43624)
			(end -0.88624 0.43624)
			(stroke
				(width 0.2)
				(type solid)
			)
			(layer "F.CrtYd")
		)
		(fp_line
			(start 0.88624 0.43624)
			(end 0.88624 -0.43624)
			(stroke
				(width 0.2)
				(type solid)
			)
			(layer "F.CrtYd")
		)
		(fp_line
			(start 0.88624 -0.43624)
			(end -0.88624 -0.43624)
			(stroke
				(width 0.2)
				(type solid)
			)
			(layer "F.CrtYd")
		)
		(fp_line
			(start 0 0.5)
			(end 0 -0.5)
			(stroke
				(width 0.1)
				(type solid)
			)
			(layer "F.Fab")
		)
		(fp_line
			(start -0.88624 0.43624)
			(end -0.88624 -0.43624)
			(stroke
				(width 0.2)
				(type solid)
			)
			(layer "F.Fab")
		)
		(fp_line
			(start 0.88624 0.43624)
			(end -0.88624 0.43624)
			(stroke
				(width 0.2)
				(type solid)
			)
			(layer "F.Fab")
		)
		(fp_line
			(start 0.88624 0.43624)
			(end 0.88624 -0.43624)
			(stroke
				(width 0.2)
				(type solid)
			)
			(layer "F.Fab")
		)
		(fp_line
			(start 0.5 0)
			(end -0.5 0)
			(stroke
				(width 0.1)
				(type solid)
			)
			(layer "F.Fab")
		)
		(fp_line
			(start 0.88624 -0.43624)
			(end -0.88624 -0.43624)
			(stroke
				(width 0.2)
				(type solid)
			)
			(layer "F.Fab")
		)
		(fp_text user "${REFERENCE}"
			(at -0.00001 0.09602 270)
			(unlocked yes)
			(layer "F.Fab")
			(effects
				(font
					(face "Arial")
					(size 0.63 0.63)
					(thickness 0.1)
				)
				(justify left bottom)
			)
		)
		(pad "1" smd rect
			(at -0.42856 0 270)
			(size 0.61535 0.57247)
			(layers "F.Cu" "F.Mask" "F.Paste")
			(net "+3V3")
			(solder_mask_margin 0)
			(solder_paste_margin 0)
		)
		(pad "2" smd rect
			(at 0.42856 0 270)
			(size 0.61535 0.57247)
			(layers "F.Cu" "F.Mask" "F.Paste")
			(net "GND")
			(solder_mask_margin 0)
			(solder_paste_margin 0)
		)
	)
	(footprint "Vault:FP-RMCF0402-MFG"
		(layer "F.Cu")
		(at 153.501105 116.3036)
		(property "Reference" "R4"
			(at -1.3 -0.180485 0)
			(unlocked yes)
			(layer "F.SilkS")
			(effects
				(font
					(face "Arial")
					(size 0.40005 0.40005)
					(thickness 0.1778)
				)
			)
		)
		(property "Value" "1k"
			(at -5.114945 5.014445 270)
			(unlocked yes)
			(layer "F.SilkS")
			(hide yes)
			(effects
				(font
					(face "Arial")
					(size 0.40005 0.40005)
					(thickness 0.1778)
				)
			)
		)
		(sheetname "01-M2_ZED-F9T_MODULE")
		(sheetfile "01-M2_ZED-F9T_MODULE.kicad_sch")
		(duplicate_pad_numbers_are_jumpers no)
		(fp_line
			(start -0.55 -0.7)
			(end 0.55 -0.7)
			(stroke
				(width 0.2)
				(type solid)
			)
			(layer "F.SilkS")
		)
		(fp_line
			(start -0.55 0.7)
			(end 0.55 0.7)
			(stroke
				(width 0.2)
				(type solid)
			)
			(layer "F.SilkS")
		)
		(fp_line
			(start -0.85 -0.4)
			(end 0.85 -0.4)
			(stroke
				(width 0.2)
				(type solid)
			)
			(layer "F.CrtYd")
		)
		(fp_line
			(start -0.85 0.4)
			(end -0.85 -0.4)
			(stroke
				(width 0.2)
				(type solid)
			)
			(layer "F.CrtYd")
		)
		(fp_line
			(start -0.85 0.4)
			(end 0.85 0.4)
			(stroke
				(width 0.2)
				(type solid)
			)
			(layer "F.CrtYd")
		)
		(fp_line
			(start 0.85 0.4)
			(end 0.85 -0.4)
			(stroke
				(width 0.2)
				(type solid)
			)
			(layer "F.CrtYd")
		)
		(fp_line
			(start -0.85 -0.4)
			(end 0.85 -0.4)
			(stroke
				(width 0.2)
				(type solid)
			)
			(layer "F.Fab")
		)
		(fp_line
			(start -0.85 0.4)
			(end -0.85 -0.4)
			(stroke
				(width 0.2)
				(type solid)
			)
			(layer "F.Fab")
		)
		(fp_line
			(start -0.85 0.4)
			(end 0.85 0.4)
			(stroke
				(width 0.2)
				(type solid)
			)
			(layer "F.Fab")
		)
		(fp_line
			(start -0.5 0)
			(end 0.5 0)
			(stroke
				(width 0.1)
				(type solid)
			)
			(layer "F.Fab")
		)
		(fp_line
			(start 0 0.5)
			(end 0 -0.5)
			(stroke
				(width 0.1)
				(type solid)
			)
			(layer "F.Fab")
		)
		(fp_line
			(start 0.85 0.4)
			(end 0.85 -0.4)
			(stroke
				(width 0.2)
				(type solid)
			)
			(layer "F.Fab")
		)
		(fp_text user "${REFERENCE}"
			(at -0.00001 0.10711 360)
			(unlocked yes)
			(layer "F.Fab")
			(effects
				(font
					(face "Arial")
					(size 0.63 0.63)
					(thickness 0.1)
				)
				(justify left bottom)
			)
		)
		(pad "1" smd rect
			(at -0.5 0)
			(size 0.5 0.6)
			(layers "F.Cu" "F.Mask" "F.Paste")
			(net "GND")
			(solder_mask_margin 0)
			(solder_paste_margin 0)
		)
		(pad "2" smd rect
			(at 0.5 0)
			(size 0.5 0.6)
			(layers "F.Cu" "F.Mask" "F.Paste")
			(net "NetD2_1")
			(solder_mask_margin 0)
			(solder_paste_margin 0)
		)
	)
	(footprint "Vault:FP-GRM31C-0_2-e0_3_0_8-IPC_C"
		(layer "F.Cu")
		(at 140.001105 119.2036 180)
		(property "Reference" "C7"
			(at -0.5 1.596754 0)
			(unlocked yes)
			(layer "F.SilkS")
			(effects
				(font
					(face "Arial")
					(size 0.48006 0.48006)
					(thickness 0.254)
				)
			)
		)
		(property "Value" "47uF_6.3V_1206"
			(at 8.366015 2.430251 180)
			(unlocked yes)
			(layer "F.SilkS")
			(hide yes)
			(effects
				(font
					(face "Arial")
					(size 0.96012 0.96012)
					(thickness 0.254)
				)
			)
		)
		(sheetname "03-M2_GoldFingers")
		(sheetfile "03-M2_GoldFingers.kicad_sch")
		(duplicate_pad_numbers_are_jumpers no)
		(fp_line
			(start 0.39847 0.9)
			(end -0.39846 0.9)
			(stroke
				(width 0.2)
				(type solid)
			)
			(layer "F.SilkS")
		)
		(fp_line
			(start 0.39847 -0.9)
			(end -0.39846 -0.9)
			(stroke
				(width 0.2)
				(type solid)
			)
			(layer "F.SilkS")
		)
		(fp_line
			(start 1.9531 1)
			(end -1.9531 1)
			(stroke
				(width 0.2)
				(type solid)
			)
			(layer "F.CrtYd")
		)
		(fp_line
			(start 1.9531 -1)
			(end 1.9531 1)
			(stroke
				(width 0.2)
				(type solid)
			)
			(layer "F.CrtYd")
		)
		(fp_line
			(start 1.9531 -1)
			(end -1.9531 -1)
			(stroke
				(width 0.2)
				(type solid)
			)
			(layer "F.CrtYd")
		)
		(fp_line
			(start -1.9531 -1)
			(end -1.9531 1)
			(stroke
				(width 0.2)
				(type solid)
			)
			(layer "F.CrtYd")
		)
		(fp_line
			(start 1.9531 1)
			(end -1.9531 1)
			(stroke
				(width 0.2)
				(type solid)
			)
			(layer "F.Fab")
		)
		(fp_line
			(start 1.9531 -1)
			(end 1.9531 1)
			(stroke
				(width 0.2)
				(type solid)
			)
			(layer "F.Fab")
		)
		(fp_line
			(start 1.9531 -1)
			(end -1.9531 -1)
			(stroke
				(width 0.2)
				(type solid)
			)
			(layer "F.Fab")
		)
		(fp_line
			(start 0.5 0)
			(end -0.5 0)
			(stroke
				(width 0.1)
				(type solid)
			)
			(layer "F.Fab")
		)
		(fp_line
			(start 0 -0.5)
			(end 0 0.5)
			(stroke
				(width 0.1)
				(type solid)
			)
			(layer "F.Fab")
		)
		(fp_line
			(start -1.9531 -1)
			(end -1.9531 1)
			(stroke
				(width 0.2)
				(type solid)
			)
			(layer "F.Fab")
		)
		(fp_text user "${REFERENCE}"
			(at -0.00001 0.09602 180)
			(unlocked yes)
			(layer "F.Fab")
			(effects
				(font
					(face "Arial")
					(size 0.63 0.63)
					(thickness 0.1)
				)
				(justify left bottom)
			)
		)
		(pad "1" smd rect
			(at -1.27578 0 180)
			(size 1.15464 1.7062)
			(layers "F.Cu" "F.Mask" "F.Paste")
			(net "+3V3")
			(solder_mask_margin 0)
			(solder_paste_margin 0)
		)
		(pad "2" smd rect
			(at 1.27578 0 180)
			(size 1.15464 1.7062)
			(layers "F.Cu" "F.Mask" "F.Paste")
			(net "GND")
			(solder_mask_margin 0)
			(solder_paste_margin 0)
		)
	)
	(footprint "Vault:HRS-U.FL-R-SMT-3_V"
		(layer "F.Cu")
		(at 154.631465 85.54119)
		(property "Reference" "P1"
			(at 3.260159 0.06241 270)
			(unlocked yes)
			(layer "F.SilkS")
			(effects
				(font
					(face "Arial")
					(size 0.96012 0.96012)
					(thickness 0.254)
				)
			)
		)
		(property "Value" "U.FL-R-SMT-1(01)"
			(at 8.619685 3.367981 0)
			(unlocked yes)
			(layer "F.SilkS")
			(hide yes)
			(effects
				(font
					(face "Arial")
					(size 0.96012 0.96012)
					(thickness 0.254)
				)
			)
		)
		(sheetname "02-Antenna_Supervisor")
		(sheetfile "02-Antenna_Supervisor.kicad_sch")
		(duplicate_pad_numbers_are_jumpers no)
		(fp_line
			(start -0.55 -1.3)
			(end 0.55 -1.3)
			(stroke
				(width 0.2)
				(type solid)
			)
			(layer "F.SilkS")
		)
		(fp_circle
			(center -2.55 0)
			(end -2.55 -0.125)
			(stroke
				(width 0.25)
				(type solid)
			)
			(fill no)
			(layer "F.SilkS")
		)
		(fp_line
			(start -2.1 -1.4)
			(end 2.1 -1.4)
			(stroke
				(width 0.05)
				(type solid)
			)
			(layer "F.CrtYd")
		)
		(fp_line
			(start -2.1 2.15)
			(end -2.1 -1.4)
			(stroke
				(width 0.05)
				(type solid)
			)
			(layer "F.CrtYd")
		)
		(fp_line
			(start -2.1 2.15)
			(end 2.1 2.15)
			(stroke
				(width 0.05)
				(type solid)
			)
			(layer "F.CrtYd")
		)
		(fp_line
			(start -0.5 0)
			(end 0.5 0)
			(stroke
				(width 0.1)
				(type solid)
			)
			(layer "F.CrtYd")
		)
		(fp_line
			(start 0 0.5)
			(end 0 -0.5)
			(stroke
				(width 0.1)
				(type solid)
			)
			(layer "F.CrtYd")
		)
		(fp_line
			(start 2.1 2.15)
			(end 2.1 -1.4)
			(stroke
				(width 0.05)
				(type solid)
			)
			(layer "F.CrtYd")
		)
		(pad "1" smd rect
			(at -1.475 0 180)
			(size 1.05 2.2)
			(layers "F.Cu" "F.Mask" "F.Paste")
			(net "GND")
		)
		(pad "2" smd rect
			(at 1.475 0 180)
			(size 1.05 2.2)
			(layers "F.Cu" "F.Mask" "F.Paste")
			(net "GND")
		)
		(pad "3" smd rect
			(at 0 1.525 180)
			(size 1 1.05)
			(layers "F.Cu" "F.Mask" "F.Paste")
			(net "RF_ANT")
		)
	)
	(footprint "Vault:FP-GRM033-0_03-IPC_B"
		(layer "F.Cu")
		(at 152.697275 89.90197 -90)
		(property "Reference" "C12"
			(at 2.104835 -0.381387 270)
			(unlocked yes)
			(layer "F.SilkS")
			(effects
				(font
					(size 0.635 0.635)
					(thickness 0.2032)
				)
			)
		)
		(property "Value" "10nF"
			(at -2.099971 2.24704 180)
			(unlocked yes)
			(layer "F.SilkS")
			(hide yes)
			(effects
				(font
					(face "Arial")
					(size 0.96012 0.96012)
					(thickness 0.254)
				)
			)
		)
		(sheetname "02-Antenna_Supervisor")
		(sheetfile "02-Antenna_Supervisor.kicad_sch")
		(duplicate_pad_numbers_are_jumpers no)
		(fp_line
			(start -0.68137 0.33137)
			(end -0.68137 -0.33137)
			(stroke
				(width 0.2)
				(type solid)
			)
			(layer "F.CrtYd")
		)
		(fp_line
			(start 0.68136 0.33137)
			(end -0.68137 0.33137)
			(stroke
				(width 0.2)
				(type solid)
			)
			(layer "F.CrtYd")
		)
		(fp_line
			(start 0.68136 0.33137)
			(end 0.68136 -0.33137)
			(stroke
				(width 0.2)
				(type solid)
			)
			(layer "F.CrtYd")
		)
		(fp_line
			(start 0.68136 -0.33137)
			(end -0.68137 -0.33137)
			(stroke
				(width 0.2)
				(type solid)
			)
			(layer "F.CrtYd")
		)
		(fp_line
			(start 0 0.5)
			(end 0 -0.5)
			(stroke
				(width 0.1)
				(type solid)
			)
			(layer "F.Fab")
		)
		(fp_line
			(start -0.68137 0.33137)
			(end -0.68137 -0.33137)
			(stroke
				(width 0.2)
				(type solid)
			)
			(layer "F.Fab")
		)
		(fp_line
			(start 0.68136 0.33137)
			(end -0.68137 0.33137)
			(stroke
				(width 0.2)
				(type solid)
			)
			(layer "F.Fab")
		)
		(fp_line
			(start 0.68136 0.33137)
			(end 0.68136 -0.33137)
			(stroke
				(width 0.2)
				(type solid)
			)
			(layer "F.Fab")
		)
		(fp_line
			(start 0.49999 0)
			(end -0.5 0)
			(stroke
				(width 0.1)
				(type solid)
			)
			(layer "F.Fab")
		)
		(fp_line
			(start 0.68136 -0.33137)
			(end -0.68137 -0.33137)
			(stroke
				(width 0.2)
				(type solid)
			)
			(layer "F.Fab")
		)
		(fp_text user "${REFERENCE}"
			(at -0.00001 0.09602 270)
			(unlocked yes)
			(layer "F.Fab")
			(effects
				(font
					(face "Arial")
					(size 0.63 0.63)
					(thickness 0.1)
				)
				(justify left bottom)
			)
		)
		(pad "1" smd rect
			(at -0.30431 0 270)
			(size 0.45411 0.36274)
			(layers "F.Cu" "F.Mask" "F.Paste")
			(net "NetC12_1")
			(solder_mask_margin 0)
			(solder_paste_margin 0)
		)
		(pad "2" smd rect
			(at 0.30431 0 270)
			(size 0.45411 0.36274)
			(layers "F.Cu" "F.Mask" "F.Paste")
			(net "GND")
			(solder_mask_margin 0)
			(solder_paste_margin 0)
		)
	)
	(footprint "Vault:FP-CL542-IPC_C"
		(layer "F.Cu")
		(at 146.303365 110.481 180)
		(property "Reference" "C1"
			(at 0.102255 -1.142115 0)
			(unlocked yes)
			(layer "F.SilkS")
			(effects
				(font
					(face "Arial")
					(size 0.40005 0.40005)
					(thickness 0.1778)
				)
			)
		)
		(property "Value" "1uF_25V_0402"
			(at 4.1259 1.959815 180)
			(unlocked yes)
			(layer "F.SilkS")
			(hide yes)
			(effects
				(font
					(face "Arial")
					(size 0.40005 0.40005)
					(thickness 0.1778)
				)
			)
		)
		(sheetname "01-M2_ZED-F9T_MODULE")
		(sheetfile "01-M2_ZED-F9T_MODULE.kicad_sch")
		(duplicate_pad_numbers_are_jumpers no)
		(fp_line
			(start 0.63624 0.67499)
			(end -0.63623 0.67499)
			(stroke
				(width 0.2)
				(type solid)
			)
			(layer "F.SilkS")
		)
		(fp_line
			(start 0.63624 -0.675)
			(end -0.63623 -0.675)
			(stroke
				(width 0.2)
				(type solid)
			)
			(layer "F.SilkS")
		)
		(fp_line
			(start 0.73624 0.375)
			(end -0.73623 0.375)
			(stroke
				(width 0.2)
				(type solid)
			)
			(layer "F.CrtYd")
		)
		(fp_line
			(start 0.73624 -0.37501)
			(end 0.73624 0.375)
			(stroke
				(width 0.2)
				(type solid)
			)
			(layer "F.CrtYd")
		)
		(fp_line
			(start 0.73624 -0.37501)
			(end -0.73623 -0.37501)
			(stroke
				(width 0.2)
				(type solid)
			)
			(layer "F.CrtYd")
		)
		(fp_line
			(start -0.73623 -0.37501)
			(end -0.73623 0.375)
			(stroke
				(width 0.2)
				(type solid)
			)
			(layer "F.CrtYd")
		)
		(fp_line
			(start 0.73624 0.375)
			(end -0.73623 0.375)
			(stroke
				(width 0.2)
				(type solid)
			)
			(layer "F.Fab")
		)
		(fp_line
			(start 0.73624 -0.37501)
			(end 0.73624 0.375)
			(stroke
				(width 0.2)
				(type solid)
			)
			(layer "F.Fab")
		)
		(fp_line
			(start 0.73624 -0.37501)
			(end -0.73623 -0.37501)
			(stroke
				(width 0.2)
				(type solid)
			)
			(layer "F.Fab")
		)
		(fp_line
			(start 0.5 0)
			(end -0.5 0)
			(stroke
				(width 0.1)
				(type solid)
			)
			(layer "F.Fab")
		)
		(fp_line
			(start 0.5 0)
			(end -0.5 0)
			(stroke
				(width 0.1)
				(type solid)
			)
			(layer "F.Fab")
		)
		(fp_line
			(start 0 -0.5)
			(end 0 0.49999)
			(stroke
				(width 0.1)
				(type solid)
			)
			(layer "F.Fab")
		)
		(fp_line
			(start 0 -0.5)
			(end 0 0.49999)
			(stroke
				(width 0.1)
				(type solid)
			)
			(layer "F.Fab")
		)
		(fp_line
			(start -0.73623 -0.37501)
			(end -0.73623 0.375)
			(stroke
				(width 0.2)
				(type solid)
			)
			(layer "F.Fab")
		)
		(fp_text user "${REFERENCE}"
			(at 0 0.28424 180)
			(unlocked yes)
			(layer "F.Fab")
			(effects
				(font
					(face "Arial")
					(size 0.63 0.63)
					(thickness 0.1)
				)
				(justify left bottom)
			)
		)
		(pad "1" smd rect
			(at -0.37856 0 180)
			(size 0.51535 0.47247)
			(layers "F.Cu" "F.Mask" "F.Paste")
			(net "+3V3")
			(solder_mask_margin 0)
			(solder_paste_margin 0)
		)
		(pad "2" smd rect
			(at 0.37857 0 180)
			(size 0.51535 0.47247)
			(layers "F.Cu" "F.Mask" "F.Paste")
			(net "GND")
			(solder_mask_margin 0)
			(solder_paste_margin 0)
		)
	)
	(footprint "Vault:FP-CRCW1218-HPe3-MFG"
		(layer "F.Cu")
		(at 149.501105 89.8036 -90)
		(property "Reference" "R16"
			(at -2.699924 -1.5 0)
			(unlocked yes)
			(layer "F.SilkS")
			(effects
				(font
					(face "Arial")
					(size 0.48006 0.48006)
					(thickness 0.254)
				)
			)
		)
		(property "Value" "22_1%_1218 1.5W"
			(at -2.385841 7.01935 180)
			(unlocked yes)
			(layer "F.SilkS")
			(hide yes)
			(effects
				(font
					(face "Arial")
					(size 0.96012 0.96012)
					(thickness 0.254)
				)
			)
		)
		(sheetname "02-Antenna_Supervisor")
		(sheetfile "02-Antenna_Supervisor.kicad_sch")
		(duplicate_pad_numbers_are_jumpers no)
		(fp_line
			(start 0.475 2.4)
			(end -0.475 2.4)
			(stroke
				(width 0.2)
				(type solid)
			)
			(layer "F.SilkS")
		)
		(fp_line
			(start 0.475 -2.4)
			(end -0.475 -2.4)
			(stroke
				(width 0.2)
				(type solid)
			)
			(layer "F.SilkS")
		)
		(fp_line
			(start -2.05 2.55)
			(end -2.05 -2.55)
			(stroke
				(width 0.2)
				(type solid)
			)
			(layer "F.CrtYd")
		)
		(fp_line
			(start 2.05 2.55)
			(end -2.05 2.55)
			(stroke
				(width 0.2)
				(type solid)
			)
			(layer "F.CrtYd")
		)
		(fp_line
			(start 2.05 2.55)
			(end 2.05 -2.55)
			(stroke
				(width 0.2)
				(type solid)
			)
			(layer "F.CrtYd")
		)
		(fp_line
			(start 2.05 -2.55)
			(end -2.05 -2.55)
			(stroke
				(width 0.2)
				(type solid)
			)
			(layer "F.CrtYd")
		)
		(fp_line
			(start -2.05 2.55)
			(end -2.05 -2.55)
			(stroke
				(width 0.2)
				(type solid)
			)
			(layer "F.Fab")
		)
		(fp_line
			(start 2.05 2.55)
			(end -2.05 2.55)
			(stroke
				(width 0.2)
				(type solid)
			)
			(layer "F.Fab")
		)
		(fp_line
			(start 2.05 2.55)
			(end 2.05 -2.55)
			(stroke
				(width 0.2)
				(type solid)
			)
			(layer "F.Fab")
		)
		(fp_line
			(start 0 0.5)
			(end 0 -0.5)
			(stroke
				(width 0.1)
				(type solid)
			)
			(layer "F.Fab")
		)
		(fp_line
			(start 0.5 0)
			(end -0.5 0)
			(stroke
				(width 0.1)
				(type solid)
			)
			(layer "F.Fab")
		)
		(fp_line
			(start 2.05 -2.55)
			(end -2.05 -2.55)
			(stroke
				(width 0.2)
				(type solid)
			)
			(layer "F.Fab")
		)
		(fp_text user "${REFERENCE}"
			(at -0.00001 0.09602 270)
			(unlocked yes)
			(layer "F.Fab")
			(effects
				(font
					(face "Arial")
					(size 0.63 0.63)
					(thickness 0.1)
				)
				(justify left bottom)
			)
		)
		(pad "1" smd rect
			(at -1.4 0 270)
			(size 1.1 4.9)
			(layers "F.Cu" "F.Mask" "F.Paste")
			(net "NetC12_1")
			(solder_mask_margin 0)
			(solder_paste_margin 0)
		)
		(pad "2" smd rect
			(at 1.4 0 270)
			(size 1.1 4.9)
			(layers "F.Cu" "F.Mask" "F.Paste")
			(net "NetQ1_3")
			(solder_mask_margin 0)
			(solder_paste_margin 0)
		)
	)
	(footprint "Vault:RESC1005X40X25NL05T10"
		(layer "F.Cu")
		(at 148.901105 118.2036 90)
		(property "Reference" "R14"
			(at 1.599995 0.504296 90)
			(unlocked yes)
			(layer "F.SilkS")
			(effects
				(font
					(face "Arial")
					(size 0.48006 0.48006)
					(thickness 0.254)
				)
			)
		)
		(property "Value" "DNI_0_5%_0402"
			(at -2.385841 9.43298 0)
			(unlocked yes)
			(layer "F.SilkS")
			(hide yes)
			(effects
				(font
					(face "Arial")
					(size 0.96012 0.96012)
					(thickness 0.254)
				)
			)
		)
		(sheetname "03-M2_GoldFingers")
		(sheetfile "03-M2_GoldFingers.kicad_sch")
		(duplicate_pad_numbers_are_jumpers no)
		(fp_line
			(start 0.9 -0.45)
			(end 0.9 0.45)
			(stroke
				(width 0.05)
				(type solid)
			)
			(layer "F.CrtYd")
		)
		(fp_line
			(start -0.9 -0.45)
			(end 0.9 -0.45)
			(stroke
				(width 0.05)
				(type solid)
			)
			(layer "F.CrtYd")
		)
		(fp_line
			(start -0.9 -0.45)
			(end -0.9 0.45)
			(stroke
				(width 0.05)
				(type solid)
			)
			(layer "F.CrtYd")
		)
		(fp_line
			(start 0 -0.275)
			(end 0 0.275)
			(stroke
				(width 0.1)
				(type solid)
			)
			(layer "F.CrtYd")
		)
		(fp_line
			(start -0.275 0)
			(end 0.275 0)
			(stroke
				(width 0.1)
				(type solid)
			)
			(layer "F.CrtYd")
		)
		(fp_line
			(start -0.9 0.45)
			(end 0.9 0.45)
			(stroke
				(width 0.05)
				(type solid)
			)
			(layer "F.CrtYd")
		)
		(pad "1" smd rect
			(at -0.425 0 180)
			(size 0.55 0.6)
			(layers "F.Cu" "F.Mask" "F.Paste")
			(net "NetJ1_35")
		)
		(pad "2" smd rect
			(at 0.425 0 180)
			(size 0.55 0.6)
			(layers "F.Cu" "F.Mask" "F.Paste")
			(net "TP1")
		)
	)
	(footprint "Vault:FP-0402-L_1_0_0_05-W_0_5-IPC_B"
		(layer "F.Cu")
		(at 140.201105 85.0036 180)
		(property "Reference" "C9"
			(at 1.799995 0.180419 0)
			(unlocked yes)
			(layer "F.SilkS")
			(effects
				(font
					(face "Arial")
					(size 0.96012 0.96012)
					(thickness 0.254)
				)
			)
		)
		(property "Value" "100nF"
			(at 2.70399 2.099971 180)
			(unlocked yes)
			(layer "F.SilkS")
			(hide yes)
			(effects
				(font
					(face "Arial")
					(size 0.96012 0.96012)
					(thickness 0.254)
				)
			)
		)
		(sheetname "02-Antenna_Supervisor")
		(sheetfile "02-Antenna_Supervisor.kicad_sch")
		(duplicate_pad_numbers_are_jumpers no)
		(fp_line
			(start 0.73624 0.68624)
			(end -0.73624 0.68624)
			(stroke
				(width 0.2)
				(type solid)
			)
			(layer "F.SilkS")
		)
		(fp_line
			(start 0.73624 -0.68624)
			(end -0.73624 -0.68624)
			(stroke
				(width 0.2)
				(type solid)
			)
			(layer "F.SilkS")
		)
		(fp_line
			(start 0.88624 0.43624)
			(end -0.88624 0.43624)
			(stroke
				(width 0.2)
				(type solid)
			)
			(layer "F.CrtYd")
		)
		(fp_line
			(start 0.88624 -0.43624)
			(end 0.88624 0.43624)
			(stroke
				(width 0.2)
				(type solid)
			)
			(layer "F.CrtYd")
		)
		(fp_line
			(start 0.88624 -0.43624)
			(end -0.88624 -0.43624)
			(stroke
				(width 0.2)
				(type solid)
			)
			(layer "F.CrtYd")
		)
		(fp_line
			(start -0.88624 -0.43624)
			(end -0.88624 0.43624)
			(stroke
				(width 0.2)
				(type solid)
			)
			(layer "F.CrtYd")
		)
		(fp_line
			(start 0.88624 0.43624)
			(end -0.88624 0.43624)
			(stroke
				(width 0.2)
				(type solid)
			)
			(layer "F.Fab")
		)
		(fp_line
			(start 0.88624 -0.43624)
			(end 0.88624 0.43624)
			(stroke
				(width 0.2)
				(type solid)
			)
			(layer "F.Fab")
		)
		(fp_line
			(start 0.88624 -0.43624)
			(end -0.88624 -0.43624)
			(stroke
				(width 0.2)
				(type solid)
			)
			(layer "F.Fab")
		)
		(fp_line
			(start 0.5 0)
			(end -0.5 0)
			(stroke
				(width 0.1)
				(type solid)
			)
			(layer "F.Fab")
		)
		(fp_line
			(start 0 -0.5)
			(end 0 0.5)
			(stroke
				(width 0.1)
				(type solid)
			)
			(layer "F.Fab")
		)
		(fp_line
			(start -0.88624 -0.43624)
			(end -0.88624 0.43624)
			(stroke
				(width 0.2)
				(type solid)
			)
			(layer "F.Fab")
		)
		(fp_text user "${REFERENCE}"
			(at -0.00001 0.09601 180)
			(unlocked yes)
			(layer "F.Fab")
			(effects
				(font
					(face "Arial")
					(size 0.63 0.63)
					(thickness 0.1)
				)
				(justify left bottom)
			)
		)
		(pad "1" smd rect
			(at -0.42856 0 180)
			(size 0.61535 0.57247)
			(layers "F.Cu" "F.Mask" "F.Paste")
			(net "+3V3")
			(solder_mask_margin 0)
			(solder_paste_margin 0)
		)
		(pad "2" smd rect
			(at 0.42856 0 180)
			(size 0.61535 0.57247)
			(layers "F.Cu" "F.Mask" "F.Paste")
			(net "GND")
			(solder_mask_margin 0)
			(solder_paste_margin 0)
		)
	)
	(footprint "Vault:FP-LTST-C191KGKT-MFG"
		(layer "F.Cu")
		(at 155.901105 116.3036)
		(property "Reference" "D2"
			(at 2.300005 -0.490519 0)
			(unlocked yes)
			(layer "F.SilkS")
			(effects
				(font
					(face "Arial")
					(size 0.96012 0.96012)
					(thickness 0.254)
				)
			)
		)
		(property "Value" "LTST-C191KGKT"
			(at 7.705865 2.207911 0)
			(unlocked yes)
			(layer "F.SilkS")
			(hide yes)
			(effects
				(font
					(face "Arial")
					(size 0.96012 0.96012)
					(thickness 0.254)
				)
			)
		)
		(sheetname "01-M2_ZED-F9T_MODULE")
		(sheetfile "01-M2_ZED-F9T_MODULE.kicad_sch")
		(duplicate_pad_numbers_are_jumpers no)
		(fp_line
			(start -0.85 -0.775)
			(end 0.85 -0.775)
			(stroke
				(width 0.2)
				(type solid)
			)
			(layer "F.SilkS")
		)
		(fp_line
			(start -0.85 0.775)
			(end 0.85 0.775)
			(stroke
				(width 0.2)
				(type solid)
			)
			(layer "F.SilkS")
		)
		(fp_circle
			(center -0.99118 1.3)
			(end -0.99118 1.175)
			(stroke
				(width 0.25)
				(type solid)
			)
			(fill no)
			(layer "F.SilkS")
		)
		(fp_line
			(start -1.25 -0.55)
			(end 1.25 -0.55)
			(stroke
				(width 0.2)
				(type solid)
			)
			(layer "F.CrtYd")
		)
		(fp_line
			(start -1.25 0.55)
			(end -1.25 -0.55)
			(stroke
				(width 0.2)
				(type solid)
			)
			(layer "F.CrtYd")
		)
		(fp_line
			(start -1.25 0.55)
			(end 1.25 0.55)
			(stroke
				(width 0.2)
				(type solid)
			)
			(layer "F.CrtYd")
		)
		(fp_line
			(start 1.25 0.55)
			(end 1.25 -0.55)
			(stroke
				(width 0.2)
				(type solid)
			)
			(layer "F.CrtYd")
		)
		(fp_line
			(start -1.25 -0.55)
			(end 1.25 -0.55)
			(stroke
				(width 0.2)
				(type solid)
			)
			(layer "F.Fab")
		)
		(fp_line
			(start -1.25 0.55)
			(end -1.25 -0.55)
			(stroke
				(width 0.2)
				(type solid)
			)
			(layer "F.Fab")
		)
		(fp_line
			(start -1.25 0.55)
			(end 1.25 0.55)
			(stroke
				(width 0.2)
				(type solid)
			)
			(layer "F.Fab")
		)
		(fp_line
			(start -0.5 0)
			(end 0.5 0)
			(stroke
				(width 0.1)
				(type solid)
			)
			(layer "F.Fab")
		)
		(fp_line
			(start 0 0.5)
			(end 0 -0.5)
			(stroke
				(width 0.1)
				(type solid)
			)
			(layer "F.Fab")
		)
		(fp_line
			(start 1.25 0.55)
			(end 1.25 -0.55)
			(stroke
				(width 0.2)
				(type solid)
			)
			(layer "F.Fab")
		)
		(fp_text user "${REFERENCE}"
			(at 0 0.29534 0)
			(unlocked yes)
			(layer "F.Fab")
			(effects
				(font
					(face "Arial")
					(size 0.63 0.63)
					(thickness 0.1)
				)
				(justify left bottom)
			)
		)
		(pad "1" smd rect
			(at -0.75 0)
			(size 0.8 0.8)
			(layers "F.Cu" "F.Mask" "F.Paste")
			(net "NetD2_1")
			(solder_mask_margin 0)
			(solder_paste_margin 0)
		)
		(pad "2" smd rect
			(at 0.75 0)
			(size 0.8 0.8)
			(layers "F.Cu" "F.Mask" "F.Paste")
			(net "TP2")
			(solder_mask_margin 0)
			(solder_paste_margin 0)
		)
	)
	(footprint "Vault:FP-PESD0402-MFG"
		(layer "F.Cu")
		(at 155.255595 88.43974 180)
		(property "Reference" "D1"
			(at -2.34551 0.126659 0)
			(unlocked yes)
			(layer "F.SilkS")
			(effects
				(font
					(face "Arial")
					(size 0.96012 0.96012)
					(thickness 0.254)
				)
			)
		)
		(property "Value" "PESD0402-140"
			(at 7.75688 2.131721 180)
			(unlocked yes)
			(layer "F.SilkS")
			(hide yes)
			(effects
				(font
					(face "Arial")
					(size 0.96012 0.96012)
					(thickness 0.254)
				)
			)
		)
		(sheetname "02-Antenna_Supervisor")
		(sheetfile "02-Antenna_Supervisor.kicad_sch")
		(duplicate_pad_numbers_are_jumpers no)
		(fp_line
			(start 1.15 0.425)
			(end -1.15 0.425)
			(stroke
				(width 0.2)
				(type solid)
			)
			(layer "F.CrtYd")
		)
		(fp_line
			(start 1.15 -0.425)
			(end 1.15 0.425)
			(stroke
				(width 0.2)
				(type solid)
			)
			(layer "F.CrtYd")
		)
		(fp_line
			(start 1.15 -0.425)
			(end -1.15 -0.425)
			(stroke
				(width 0.2)
				(type solid)
			)
			(layer "F.CrtYd")
		)
		(fp_line
			(start -1.15 -0.425)
			(end -1.15 0.425)
			(stroke
				(width 0.2)
				(type solid)
			)
			(layer "F.CrtYd")
		)
		(fp_line
			(start 1.15 0.425)
			(end -1.15 0.425)
			(stroke
				(width 0.2)
				(type solid)
			)
			(layer "F.Fab")
		)
		(fp_line
			(start 1.15 -0.425)
			(end 1.15 0.425)
			(stroke
				(width 0.2)
				(type solid)
			)
			(layer "F.Fab")
		)
		(fp_line
			(start 1.15 -0.425)
			(end -1.15 -0.425)
			(stroke
				(width 0.2)
				(type solid)
			)
			(layer "F.Fab")
		)
		(fp_line
			(start 0.5 0)
			(end -0.49999 0)
			(stroke
				(width 0.1)
				(type solid)
			)
			(layer "F.Fab")
		)
		(fp_line
			(start 0 -0.49999)
			(end 0 0.5)
			(stroke
				(width 0.1)
				(type solid)
			)
			(layer "F.Fab")
		)
		(fp_line
			(start -1.15 -0.425)
			(end -1.15 0.425)
			(stroke
				(width 0.2)
				(type solid)
			)
			(layer "F.Fab")
		)
		(fp_text user "${REFERENCE}"
			(at -0.00001 0.10712 180)
			(unlocked yes)
			(layer "F.Fab")
			(effects
				(font
					(face "Arial")
					(size 0.63 0.63)
					(thickness 0.1)
				)
				(justify left bottom)
			)
		)
		(pad "1" smd rect
			(at -0.625 0 180)
			(size 0.85 0.65)
			(layers "F.Cu" "F.Mask" "F.Paste")
			(net "GND")
			(solder_mask_margin 0)
			(solder_paste_margin 0)
		)
		(pad "2" smd rect
			(at 0.625 0 180)
			(size 0.85 0.65)
			(layers "F.Cu" "F.Mask" "F.Paste")
			(net "RF_ANT")
			(solder_mask_margin 0)
			(solder_paste_margin 0)
		)
	)
	(footprint "Vault:RESC1005X40X25NL05T10"
		(layer "F.Cu")
		(at 145.401105 114.8036 180)
		(property "Reference" "R2"
			(at 2.099995 0.095704 0)
			(unlocked yes)
			(layer "F.SilkS")
			(effects
				(font
					(face "Arial")
					(size 0.48006 0.48006)
					(thickness 0.254)
				)
			)
		)
		(property "Value" "0_5%_0402"
			(at 7.604675 1.877841 180)
			(unlocked yes)
			(layer "F.SilkS")
			(hide yes)
			(effects
				(font
					(face "Arial")
					(size 0.96012 0.96012)
					(thickness 0.254)
				)
			)
		)
		(sheetname "01-M2_ZED-F9T_MODULE")
		(sheetfile "01-M2_ZED-F9T_MODULE.kicad_sch")
		(duplicate_pad_numbers_are_jumpers no)
		(fp_line
			(start 0.9 0.45)
			(end -0.9 0.45)
			(stroke
				(width 0.05)
				(type solid)
			)
			(layer "F.CrtYd")
		)
		(fp_line
			(start 0.9 -0.45)
			(end 0.9 0.45)
			(stroke
				(width 0.05)
				(type solid)
			)
			(layer "F.CrtYd")
		)
		(fp_line
			(start 0.9 -0.45)
			(end -0.9 -0.45)
			(stroke
				(width 0.05)
				(type solid)
			)
			(layer "F.CrtYd")
		)
		(fp_line
			(start 0.275 0)
			(end -0.275 0)
			(stroke
				(width 0.1)
				(type solid)
			)
			(layer "F.CrtYd")
		)
		(fp_line
			(start 0 -0.275)
			(end 0 0.275)
			(stroke
				(width 0.1)
				(type solid)
			)
			(layer "F.CrtYd")
		)
		(fp_line
			(start -0.9 -0.45)
			(end -0.9 0.45)
			(stroke
				(width 0.05)
				(type solid)
			)
			(layer "F.CrtYd")
		)
		(pad "1" smd rect
			(at -0.425 0 270)
			(size 0.55 0.6)
			(layers "F.Cu" "F.Mask" "F.Paste")
			(net "TX_GPS_CONN")
		)
		(pad "2" smd rect
			(at 0.425 0 270)
			(size 0.55 0.6)
			(layers "F.Cu" "F.Mask" "F.Paste")
			(net "NetR2_2")
		)
	)
	(footprint "GNSS_Receiver_Library:GPS_ZED-F9T"
		(locked yes)
		(layer "F.Cu")
		(at 155.701105 93.84359 180)
		(property "Reference" "U1"
			(at -3 1.84474 0)
			(unlocked yes)
			(layer "F.SilkS")
			(effects
				(font
					(face "Arial")
					(size 0.504 0.504)
					(thickness 0.15)
				)
			)
		)
		(property "Value" "ZED-F9T-00B"
			(at 3.059145 -26.098741 0)
			(unlocked yes)
			(layer "F.SilkS")
			(hide yes)
			(effects
				(font
					(face "Arial")
					(size 0.96012 0.96012)
					(thickness 0.254)
				)
			)
		)
		(sheetname "01-M2_ZED-F9T_MODULE")
		(sheetfile "01-M2_ZED-F9T_MODULE.kicad_sch")
		(duplicate_pad_numbers_are_jumpers no)
		(fp_circle
			(center -0.5 2.23999)
			(end -0.5 2.31619)
			(stroke
				(width 0.762)
				(type solid)
			)
			(fill no)
			(layer "F.SilkS")
		)
		(pad "1" smd rect
			(at 0 0 180)
			(size 0.8 1.5)
			(layers "F.Cu" "F.Mask" "F.Paste")
			(net "GND")
		)
		(pad "2" smd rect
			(at 1.1 0 180)
			(size 0.8 1.5)
			(layers "F.Cu" "F.Mask" "F.Paste")
			(net "RF_IN")
		)
		(pad "3" smd rect
			(at 2.2 0 180)
			(size 0.8 1.5)
			(layers "F.Cu" "F.Mask" "F.Paste")
			(net "GND")
		)
		(pad "4" smd rect
			(at 3.3 0 180)
			(size 0.8 1.5)
			(layers "F.Cu" "F.Mask" "F.Paste")
			(net "ANT_DET")
		)
		(pad "5" smd rect
			(at 4.4 0 180)
			(size 0.8 1.5)
			(layers "F.Cu" "F.Mask" "F.Paste")
			(net "ANT_OFF")
		)
		(pad "6" smd rect
			(at 5.5 0 180)
			(size 0.8 1.5)
			(layers "F.Cu" "F.Mask" "F.Paste")
			(net "ANT_SHORT_N")
		)
		(pad "7" smd rect
			(at 6.6 0 180)
			(size 0.8 1.5)
			(layers "F.Cu" "F.Mask" "F.Paste")
		)
		(pad "8" smd rect
			(at 7.7 0 180)
			(size 0.8 1.5)
			(layers "F.Cu" "F.Mask" "F.Paste")
		)
		(pad "9" smd rect
			(at 8.8 0 180)
			(size 0.8 1.5)
			(layers "F.Cu" "F.Mask" "F.Paste")
		)
		(pad "10" smd rect
			(at 9.9 0 180)
			(size 0.8 1.5)
			(layers "F.Cu" "F.Mask" "F.Paste")
		)
		(pad "11" smd rect
			(at 11 0 180)
			(size 0.8 1.5)
			(layers "F.Cu" "F.Mask" "F.Paste")
		)
		(pad "12" smd rect
			(at 12.1 0 180)
			(size 0.8 1.5)
			(layers "F.Cu" "F.Mask" "F.Paste")
			(net "GND")
		)
		(pad "13" smd rect
			(at 13.2 0 180)
			(size 0.8 1.5)
			(layers "F.Cu" "F.Mask" "F.Paste")
		)
		(pad "14" smd rect
			(at 14.3 0 180)
			(size 0.8 1.5)
			(layers "F.Cu" "F.Mask" "F.Paste")
			(net "GND")
		)
		(pad "15" smd rect
			(at 17.1 -0.85 270)
			(size 0.8 1.5)
			(layers "F.Cu" "F.Mask" "F.Paste")
		)
		(pad "16" smd rect
			(at 17.1 -1.95 270)
			(size 0.8 1.5)
			(layers "F.Cu" "F.Mask" "F.Paste")
		)
		(pad "17" smd rect
			(at 17.1 -3.05 270)
			(size 0.8 1.5)
			(layers "F.Cu" "F.Mask" "F.Paste")
		)
		(pad "18" smd rect
			(at 17.1 -4.15 270)
			(size 0.8 1.5)
			(layers "F.Cu" "F.Mask" "F.Paste")
		)
		(pad "19" smd rect
			(at 17.1 -5.25 270)
			(size 0.8 1.5)
			(layers "F.Cu" "F.Mask" "F.Paste")
		)
		(pad "20" smd rect
			(at 17.1 -6.35 270)
			(size 0.8 1.5)
			(layers "F.Cu" "F.Mask" "F.Paste")
		)
		(pad "21" smd rect
			(at 17.1 -7.45 270)
			(size 0.8 1.5)
			(layers "F.Cu" "F.Mask" "F.Paste")
		)
		(pad "22" smd rect
			(at 17.1 -8.55 270)
			(size 0.8 1.5)
			(layers "F.Cu" "F.Mask" "F.Paste")
		)
		(pad "23" smd rect
			(at 17.1 -9.65 270)
			(size 0.8 1.5)
			(layers "F.Cu" "F.Mask" "F.Paste")
		)
		(pad "24" smd rect
			(at 17.1 -10.75 270)
			(size 0.8 1.5)
			(layers "F.Cu" "F.Mask" "F.Paste")
		)
		(pad "25" smd rect
			(at 17.1 -11.85 270)
			(size 0.8 1.5)
			(layers "F.Cu" "F.Mask" "F.Paste")
		)
		(pad "26" smd rect
			(at 17.1 -12.95 270)
			(size 0.8 1.5)
			(layers "F.Cu" "F.Mask" "F.Paste")
		)
		(pad "27" smd rect
			(at 17.1 -14.05 270)
			(size 0.8 1.5)
			(layers "F.Cu" "F.Mask" "F.Paste")
		)
		(pad "28" smd rect
			(at 14.3 -14.9 180)
			(size 0.8 1.5)
			(layers "F.Cu" "F.Mask" "F.Paste")
		)
		(pad "29" smd rect
			(at 13.2 -14.9 180)
			(size 0.8 1.5)
			(layers "F.Cu" "F.Mask" "F.Paste")
		)
		(pad "30" smd rect
			(at 12.1 -14.9 180)
			(size 0.8 1.5)
			(layers "F.Cu" "F.Mask" "F.Paste")
		)
		(pad "31" smd rect
			(at 11 -14.9 180)
			(size 0.8 1.5)
			(layers "F.Cu" "F.Mask" "F.Paste")
		)
		(pad "32" smd rect
			(at 9.9 -14.9 180)
			(size 0.8 1.5)
			(layers "F.Cu" "F.Mask" "F.Paste")
			(net "GND")
		)
		(pad "33" smd rect
			(at 8.8 -14.9 180)
			(size 0.8 1.5)
			(layers "F.Cu" "F.Mask" "F.Paste")
			(net "+3V3")
		)
		(pad "34" smd rect
			(at 7.7 -14.9 180)
			(size 0.8 1.5)
			(layers "F.Cu" "F.Mask" "F.Paste")
			(net "+3V3")
		)
		(pad "35" smd rect
			(at 6.6 -14.9 180)
			(size 0.8 1.5)
			(layers "F.Cu" "F.Mask" "F.Paste")
		)
		(pad "36" smd rect
			(at 5.5 -14.9 180)
			(size 0.8 1.5)
			(layers "F.Cu" "F.Mask" "F.Paste")
			(net "+3V3")
		)
		(pad "37" smd rect
			(at 4.4 -14.9 180)
			(size 0.8 1.5)
			(layers "F.Cu" "F.Mask" "F.Paste")
			(net "GND")
		)
		(pad "38" smd rect
			(at 3.3 -14.9 180)
			(size 0.8 1.5)
			(layers "F.Cu" "F.Mask" "F.Paste")
			(net "GND")
		)
		(pad "39" smd rect
			(at 2.2 -14.9 180)
			(size 0.8 1.5)
			(layers "F.Cu" "F.Mask" "F.Paste")
			(net "USB_D_N")
		)
		(pad "40" smd rect
			(at 1.1 -14.9 180)
			(size 0.8 1.5)
			(layers "F.Cu" "F.Mask" "F.Paste")
			(net "USB_D_P")
		)
		(pad "41" smd rect
			(at 0 -14.9 180)
			(size 0.8 1.5)
			(layers "F.Cu" "F.Mask" "F.Paste")
			(net "GND")
		)
		(pad "42" smd rect
			(at -2.8 -14.05 270)
			(size 0.8 1.5)
			(layers "F.Cu" "F.Mask" "F.Paste")
			(net "NetR2_2")
		)
		(pad "43" smd rect
			(at -2.8 -12.95 270)
			(size 0.8 1.5)
			(layers "F.Cu" "F.Mask" "F.Paste")
			(net "NetR3_2")
		)
		(pad "44" smd rect
			(at -2.8 -11.85 270)
			(size 0.8 1.5)
			(layers "F.Cu" "F.Mask" "F.Paste")
			(net "SDA")
		)
		(pad "45" smd rect
			(at -2.8 -10.75 270)
			(size 0.8 1.5)
			(layers "F.Cu" "F.Mask" "F.Paste")
			(net "SCL")
		)
		(pad "46" smd rect
			(at -2.8 -9.65 270)
			(size 0.8 1.5)
			(layers "F.Cu" "F.Mask" "F.Paste")
		)
		(pad "47" smd rect
			(at -2.8 -8.55 270)
			(size 0.8 1.5)
			(layers "F.Cu" "F.Mask" "F.Paste")
			(net "NetC5_2")
		)
		(pad "48" smd rect
			(at -2.8 -7.45 270)
			(size 0.8 1.5)
			(layers "F.Cu" "F.Mask" "F.Paste")
			(net "GND")
		)
		(pad "49" smd rect
			(at -2.8 -6.35 270)
			(size 0.8 1.5)
			(layers "F.Cu" "F.Mask" "F.Paste")
			(net "RST_GPS")
		)
		(pad "50" smd rect
			(at -2.8 -5.25 270)
			(size 0.8 1.5)
			(layers "F.Cu" "F.Mask" "F.Paste")
		)
		(pad "51" smd rect
			(at -2.8 -4.15 270)
			(size 0.8 1.5)
			(layers "F.Cu" "F.Mask" "F.Paste")
		)
		(pad "52" smd rect
			(at -2.8 -3.05 270)
			(size 0.8 1.5)
			(layers "F.Cu" "F.Mask" "F.Paste")
		)
		(pad "53" smd rect
			(at -2.8 -1.95 270)
			(size 0.8 1.5)
			(layers "F.Cu" "F.Mask" "F.Paste")
			(net "TP1")
		)
		(pad "54" smd rect
			(at -2.8 -0.85 270)
			(size 0.8 1.5)
			(layers "F.Cu" "F.Mask" "F.Paste")
			(net "TP2")
		)
		(pad "55" smd rect
			(at -0.2 -12.69998 180)
			(size 1.1 1.1)
			(layers "F.Cu" "F.Mask" "F.Paste")
			(net "GND")
		)
		(pad "55" smd rect
			(at -0.2 -10.59999 180)
			(size 1.1 1.1)
			(layers "F.Cu" "F.Mask" "F.Paste")
			(net "GND")
		)
		(pad "55" smd rect
			(at -0.2 -8.49999 180)
			(size 1.1 1.1)
			(layers "F.Cu" "F.Mask" "F.Paste")
			(net "GND")
		)
		(pad "55" smd rect
			(at -0.2 -6.4 180)
			(size 1.1 1.1)
			(layers "F.Cu" "F.Mask" "F.Paste")
			(net "GND")
		)
		(pad "55" smd rect
			(at -0.2 -4.3 180)
			(size 1.1 1.1)
			(layers "F.Cu" "F.Mask" "F.Paste")
			(net "GND")
		)
		(pad "55" smd rect
			(at -0.2 -2.2 180)
			(size 1.1 1.1)
			(layers "F.Cu" "F.Mask" "F.Paste")
			(net "GND")
		)
		(pad "55" smd rect
			(at 1.9 -12.69998 180)
			(size 1.1 1.1)
			(layers "F.Cu" "F.Mask" "F.Paste")
			(net "GND")
		)
		(pad "55" smd rect
			(at 1.9 -10.59998 180)
			(size 1.1 1.1)
			(layers "F.Cu" "F.Mask" "F.Paste")
			(net "GND")
		)
		(pad "55" smd rect
			(at 1.9 -8.49999 180)
			(size 1.1 1.1)
			(layers "F.Cu" "F.Mask" "F.Paste")
			(net "GND")
		)
		(pad "55" smd rect
			(at 1.9 -6.39999 180)
			(size 1.1 1.1)
			(layers "F.Cu" "F.Mask" "F.Paste")
			(net "GND")
		)
		(pad "55" smd rect
			(at 1.9 -4.29999 180)
			(size 1.1 1.1)
			(layers "F.Cu" "F.Mask" "F.Paste")
			(net "GND")
		)
		(pad "55" smd rect
			(at 1.9 -2.2 180)
			(size 1.1 1.1)
			(layers "F.Cu" "F.Mask" "F.Paste")
			(net "GND")
		)
		(pad "55" smd rect
			(at 4 -12.69998 180)
			(size 1.1 1.1)
			(layers "F.Cu" "F.Mask" "F.Paste")
			(net "GND")
		)
		(pad "55" smd rect
			(at 4 -10.59998 180)
			(size 1.1 1.1)
			(layers "F.Cu" "F.Mask" "F.Paste")
			(net "GND")
		)
		(pad "55" smd rect
			(at 4 -8.49999 180)
			(size 1.1 1.1)
			(layers "F.Cu" "F.Mask" "F.Paste")
			(net "GND")
		)
		(pad "55" smd rect
			(at 4 -6.39999 180)
			(size 1.1 1.1)
			(layers "F.Cu" "F.Mask" "F.Paste")
			(net "GND")
		)
		(pad "55" smd rect
			(at 4 -4.29999 180)
			(size 1.1 1.1)
			(layers "F.Cu" "F.Mask" "F.Paste")
			(net "GND")
		)
		(pad "55" smd rect
			(at 4 -2.2 180)
			(size 1.1 1.1)
			(layers "F.Cu" "F.Mask" "F.Paste")
			(net "GND")
		)
		(pad "55" smd rect
			(at 6.1 -12.69998 180)
			(size 1.1 1.1)
			(layers "F.Cu" "F.Mask" "F.Paste")
			(net "GND")
		)
		(pad "55" smd rect
			(at 6.1 -10.59998 180)
			(size 1.1 1.1)
			(layers "F.Cu" "F.Mask" "F.Paste")
			(net "GND")
		)
		(pad "55" smd rect
			(at 6.1 -8.49999 180)
			(size 1.1 1.1)
			(layers "F.Cu" "F.Mask" "F.Paste")
			(net "GND")
		)
		(pad "55" smd rect
			(at 6.1 -6.39999 180)
			(size 1.1 1.1)
			(layers "F.Cu" "F.Mask" "F.Paste")
			(net "GND")
		)
		(pad "55" smd rect
			(at 6.1 -4.29999 180)
			(size 1.1 1.1)
			(layers "F.Cu" "F.Mask" "F.Paste")
			(net "GND")
		)
		(pad "55" smd rect
			(at 6.1 -2.2 180)
			(size 1.1 1.1)
			(layers "F.Cu" "F.Mask" "F.Paste")
			(net "GND")
		)
		(pad "55" smd rect
			(at 8.2 -12.69998 180)
			(size 1.1 1.1)
			(layers "F.Cu" "F.Mask" "F.Paste")
			(net "GND")
		)
		(pad "55" smd rect
			(at 8.2 -10.59998 180)
			(size 1.1 1.1)
			(layers "F.Cu" "F.Mask" "F.Paste")
			(net "GND")
		)
		(pad "55" smd rect
			(at 8.2 -8.49999 180)
			(size 1.1 1.1)
			(layers "F.Cu" "F.Mask" "F.Paste")
			(net "GND")
		)
		(pad "55" smd rect
			(at 8.2 -6.39999 180)
			(size 1.1 1.1)
			(layers "F.Cu" "F.Mask" "F.Paste")
			(net "GND")
		)
		(pad "55" smd rect
			(at 8.2 -4.29999 180)
			(size 1.1 1.1)
			(layers "F.Cu" "F.Mask" "F.Paste")
			(net "GND")
		)
		(pad "55" smd rect
			(at 8.2 -2.2 180)
			(size 1.1 1.1)
			(layers "F.Cu" "F.Mask" "F.Paste")
			(net "GND")
		)
		(pad "55" smd rect
			(at 10.3 -12.69998 180)
			(size 1.1 1.1)
			(layers "F.Cu" "F.Mask" "F.Paste")
			(net "GND")
		)
		(pad "55" smd rect
			(at 10.3 -10.59998 180)
			(size 1.1 1.1)
			(layers "F.Cu" "F.Mask" "F.Paste")
			(net "GND")
		)
		(pad "55" smd rect
			(at 10.3 -8.49999 180)
			(size 1.1 1.1)
			(layers "F.Cu" "F.Mask" "F.Paste")
			(net "GND")
		)
		(pad "55" smd rect
			(at 10.3 -6.39999 180)
			(size 1.1 1.1)
			(layers "F.Cu" "F.Mask" "F.Paste")
			(net "GND")
		)
		(pad "55" smd rect
			(at 10.3 -4.29999 180)
			(size 1.1 1.1)
			(layers "F.Cu" "F.Mask" "F.Paste")
			(net "GND")
		)
		(pad "55" smd rect
			(at 10.3 -2.2 180)
			(size 1.1 1.1)
			(layers "F.Cu" "F.Mask" "F.Paste")
			(net "GND")
		)
		(pad "55" smd rect
			(at 12.4 -12.69998 180)
			(size 1.1 1.1)
			(layers "F.Cu" "F.Mask" "F.Paste")
			(net "GND")
		)
		(pad "55" smd rect
			(at 12.4 -10.59998 180)
			(size 1.1 1.1)
			(layers "F.Cu" "F.Mask" "F.Paste")
			(net "GND")
		)
		(pad "55" smd rect
			(at 12.4 -8.49999 180)
			(size 1.1 1.1)
			(layers "F.Cu" "F.Mask" "F.Paste")
			(net "GND")
		)
		(pad "55" smd rect
			(at 12.4 -6.39999 180)
			(size 1.1 1.1)
			(layers "F.Cu" "F.Mask" "F.Paste")
			(net "GND")
		)
		(pad "55" smd rect
			(at 12.4 -4.29999 180)
			(size 1.1 1.1)
			(layers "F.Cu" "F.Mask" "F.Paste")
			(net "GND")
		)
		(pad "55" smd rect
			(at 12.4 -2.2 180)
			(size 1.1 1.1)
			(layers "F.Cu" "F.Mask" "F.Paste")
			(net "GND")
		)
		(pad "55" smd rect
			(at 14.5 -12.69998 180)
			(size 1.1 1.1)
			(layers "F.Cu" "F.Mask" "F.Paste")
			(net "GND")
		)
		(pad "55" smd rect
			(at 14.5 -10.59998 180)
			(size 1.1 1.1)
			(layers "F.Cu" "F.Mask" "F.Paste")
			(net "GND")
		)
		(pad "55" smd rect
			(at 14.5 -8.49999 180)
			(size 1.1 1.1)
			(layers "F.Cu" "F.Mask" "F.Paste")
			(net "GND")
		)
		(pad "55" smd rect
			(at 14.5 -6.39999 180)
			(size 1.1 1.1)
			(layers "F.Cu" "F.Mask" "F.Paste")
			(net "GND")
		)
		(pad "55" smd rect
			(at 14.5 -4.29999 180)
			(size 1.1 1.1)
			(layers "F.Cu" "F.Mask" "F.Paste")
			(net "GND")
		)
		(pad "55" smd rect
			(at 14.5 -2.2 180)
			(size 1.1 1.1)
			(layers "F.Cu" "F.Mask" "F.Paste")
			(net "GND")
		)
	)
	(footprint "Vault:FP-RMCF0402-MFG"
		(layer "F.Cu")
		(at 143.901105 112.0036 180)
		(property "Reference" "R1"
			(at 0.1 1.279605 0)
			(unlocked yes)
			(layer "F.SilkS")
			(effects
				(font
					(face "Arial")
					(size 0.40005 0.40005)
					(thickness 0.1778)
				)
			)
		)
		(property "Value" "1k"
			(at 2.729345 2.066945 180)
			(unlocked yes)
			(layer "F.SilkS")
			(hide yes)
			(effects
				(font
					(face "Arial")
					(size 0.40005 0.40005)
					(thickness 0.1778)
				)
			)
		)
		(sheetname "01-M2_ZED-F9T_MODULE")
		(sheetfile "01-M2_ZED-F9T_MODULE.kicad_sch")
		(duplicate_pad_numbers_are_jumpers no)
		(fp_line
			(start 0.55 0.7)
			(end -0.55 0.7)
			(stroke
				(width 0.2)
				(type solid)
			)
			(layer "F.SilkS")
		)
		(fp_line
			(start 0.55 -0.7)
			(end -0.55 -0.7)
			(stroke
				(width 0.2)
				(type solid)
			)
			(layer "F.SilkS")
		)
		(fp_line
			(start 0.85 0.4)
			(end -0.85 0.4)
			(stroke
				(width 0.2)
				(type solid)
			)
			(layer "F.CrtYd")
		)
		(fp_line
			(start 0.85 -0.4)
			(end 0.85 0.4)
			(stroke
				(width 0.2)
				(type solid)
			)
			(layer "F.CrtYd")
		)
		(fp_line
			(start 0.85 -0.4)
			(end -0.85 -0.4)
			(stroke
				(width 0.2)
				(type solid)
			)
			(layer "F.CrtYd")
		)
		(fp_line
			(start -0.85 -0.4)
			(end -0.85 0.4)
			(stroke
				(width 0.2)
				(type solid)
			)
			(layer "F.CrtYd")
		)
		(fp_line
			(start 0.85 0.4)
			(end -0.85 0.4)
			(stroke
				(width 0.2)
				(type solid)
			)
			(layer "F.Fab")
		)
		(fp_line
			(start 0.85 -0.4)
			(end 0.85 0.4)
			(stroke
				(width 0.2)
				(type solid)
			)
			(layer "F.Fab")
		)
		(fp_line
			(start 0.85 -0.4)
			(end -0.85 -0.4)
			(stroke
				(width 0.2)
				(type solid)
			)
			(layer "F.Fab")
		)
		(fp_line
			(start 0.5 0)
			(end -0.5 0)
			(stroke
				(width 0.1)
				(type solid)
			)
			(layer "F.Fab")
		)
		(fp_line
			(start 0 -0.5)
			(end 0 0.5)
			(stroke
				(width 0.1)
				(type solid)
			)
			(layer "F.Fab")
		)
		(fp_line
			(start -0.85 -0.4)
			(end -0.85 0.4)
			(stroke
				(width 0.2)
				(type solid)
			)
			(layer "F.Fab")
		)
		(fp_text user "${REFERENCE}"
			(at -0.00001 0.10711 180)
			(unlocked yes)
			(layer "F.Fab")
			(effects
				(font
					(face "Arial")
					(size 0.63 0.63)
					(thickness 0.1)
				)
				(justify left bottom)
			)
		)
		(pad "1" smd rect
			(at -0.5 0 180)
			(size 0.5 0.6)
			(layers "F.Cu" "F.Mask" "F.Paste")
			(net "NetC5_2")
			(solder_mask_margin 0)
			(solder_paste_margin 0)
		)
		(pad "2" smd rect
			(at 0.5 0 180)
			(size 0.5 0.6)
			(layers "F.Cu" "F.Mask" "F.Paste")
			(net "+3V3")
			(solder_mask_margin 0)
			(solder_paste_margin 0)
		)
	)
	(footprint "Vault:FP-CL542-IPC_C"
		(layer "F.Cu")
		(at 150.701105 111.5036)
		(property "Reference" "C4"
			(at 1.284665 0.419515 0)
			(unlocked yes)
			(layer "F.SilkS")
			(effects
				(font
					(face "Arial")
					(size 0.40005 0.40005)
					(thickness 0.1778)
				)
			)
		)
		(property "Value" "1uF_25V_0402"
			(at 5.01461 2.213735 0)
			(unlocked yes)
			(layer "F.SilkS")
			(hide yes)
			(effects
				(font
					(face "Arial")
					(size 0.40005 0.40005)
					(thickness 0.1778)
				)
			)
		)
		(sheetname "01-M2_ZED-F9T_MODULE")
		(sheetfile "01-M2_ZED-F9T_MODULE.kicad_sch")
		(duplicate_pad_numbers_are_jumpers no)
		(fp_line
			(start -0.73624 -0.375)
			(end 0.73624 -0.375)
			(stroke
				(width 0.2)
				(type solid)
			)
			(layer "F.CrtYd")
		)
		(fp_line
			(start -0.73624 0.375)
			(end -0.73624 -0.375)
			(stroke
				(width 0.2)
				(type solid)
			)
			(layer "F.CrtYd")
		)
		(fp_line
			(start -0.73624 0.375)
			(end 0.73624 0.375)
			(stroke
				(width 0.2)
				(type solid)
			)
			(layer "F.CrtYd")
		)
		(fp_line
			(start 0.73624 0.375)
			(end 0.73624 -0.375)
			(stroke
				(width 0.2)
				(type solid)
			)
			(layer "F.CrtYd")
		)
		(fp_line
			(start -0.73624 -0.375)
			(end 0.73624 -0.375)
			(stroke
				(width 0.2)
				(type solid)
			)
			(layer "F.Fab")
		)
		(fp_line
			(start -0.73624 0.375)
			(end -0.73624 -0.375)
			(stroke
				(width 0.2)
				(type solid)
			)
			(layer "F.Fab")
		)
		(fp_line
			(start -0.73624 0.375)
			(end 0.73624 0.375)
			(stroke
				(width 0.2)
				(type solid)
			)
			(layer "F.Fab")
		)
		(fp_line
			(start -0.5 0)
			(end 0.5 0)
			(stroke
				(width 0.1)
				(type solid)
			)
			(layer "F.Fab")
		)
		(fp_line
			(start -0.5 0)
			(end 0.5 0)
			(stroke
				(width 0.1)
				(type solid)
			)
			(layer "F.Fab")
		)
		(fp_line
			(start 0 0.5)
			(end 0 -0.5)
			(stroke
				(width 0.1)
				(type solid)
			)
			(layer "F.Fab")
		)
		(fp_line
			(start 0 0.5)
			(end 0 -0.5)
			(stroke
				(width 0.1)
				(type solid)
			)
			(layer "F.Fab")
		)
		(fp_line
			(start 0.73624 0.375)
			(end 0.73624 -0.375)
			(stroke
				(width 0.2)
				(type solid)
			)
			(layer "F.Fab")
		)
		(fp_text user "${REFERENCE}"
			(at 0 0.28425 360)
			(unlocked yes)
			(layer "F.Fab")
			(effects
				(font
					(face "Arial")
					(size 0.63 0.63)
					(thickness 0.1)
				)
				(justify left bottom)
			)
		)
		(pad "1" smd rect
			(at -0.37856 0)
			(size 0.51535 0.47247)
			(layers "F.Cu" "F.Mask" "F.Paste")
			(net "+3V3")
			(solder_mask_margin 0)
			(solder_paste_margin 0)
		)
		(pad "2" smd rect
			(at 0.37856 0)
			(size 0.51535 0.47247)
			(layers "F.Cu" "F.Mask" "F.Paste")
			(net "GND")
			(solder_mask_margin 0)
			(solder_paste_margin 0)
		)
	)
	(footprint "Vault:FP-0402-L_1_0_0_05-W_0_5-IPC_B"
		(layer "F.Cu")
		(at 154.601105 91.1036 90)
		(property "Reference" "C10"
			(at -0.20001 2.992629 270)
			(unlocked yes)
			(layer "F.SilkS")
			(effects
				(font
					(face "Arial")
					(size 0.96012 0.96012)
					(thickness 0.254)
				)
			)
		)
		(property "Value" "100nF"
			(at -2.303171 2.90719 0)
			(unlocked yes)
			(layer "F.SilkS")
			(hide yes)
			(effects
				(font
					(face "Arial")
					(size 0.96012 0.96012)
					(thickness 0.254)
				)
			)
		)
		(sheetname "02-Antenna_Supervisor")
		(sheetfile "02-Antenna_Supervisor.kicad_sch")
		(duplicate_pad_numbers_are_jumpers no)
		(fp_line
			(start 0.88624 -0.43624)
			(end 0.88624 0.43624)
			(stroke
				(width 0.2)
				(type solid)
			)
			(layer "F.CrtYd")
		)
		(fp_line
			(start -0.88624 -0.43624)
			(end 0.88624 -0.43624)
			(stroke
				(width 0.2)
				(type solid)
			)
			(layer "F.CrtYd")
		)
		(fp_line
			(start -0.88624 -0.43624)
			(end -0.88624 0.43624)
			(stroke
				(width 0.2)
				(type solid)
			)
			(layer "F.CrtYd")
		)
		(fp_line
			(start -0.88624 0.43624)
			(end 0.88624 0.43624)
			(stroke
				(width 0.2)
				(type solid)
			)
			(layer "F.CrtYd")
		)
		(fp_line
			(start 0 -0.5)
			(end 0 0.5)
			(stroke
				(width 0.1)
				(type solid)
			)
			(layer "F.Fab")
		)
		(fp_line
			(start 0.88624 -0.43624)
			(end 0.88624 0.43624)
			(stroke
				(width 0.2)
				(type solid)
			)
			(layer "F.Fab")
		)
		(fp_line
			(start -0.88624 -0.43624)
			(end 0.88624 -0.43624)
			(stroke
				(width 0.2)
				(type solid)
			)
			(layer "F.Fab")
		)
		(fp_line
			(start -0.88624 -0.43624)
			(end -0.88624 0.43624)
			(stroke
				(width 0.2)
				(type solid)
			)
			(layer "F.Fab")
		)
		(fp_line
			(start -0.5 0)
			(end 0.5 0)
			(stroke
				(width 0.1)
				(type solid)
			)
			(layer "F.Fab")
		)
		(fp_line
			(start -0.88624 0.43624)
			(end 0.88624 0.43624)
			(stroke
				(width 0.2)
				(type solid)
			)
			(layer "F.Fab")
		)
		(fp_text user "${REFERENCE}"
			(at -0.00001 0.09602 90)
			(unlocked yes)
			(layer "F.Fab")
			(effects
				(font
					(face "Arial")
					(size 0.63 0.63)
					(thickness 0.1)
				)
				(justify left bottom)
			)
		)
		(pad "1" smd rect
			(at -0.42856 0 90)
			(size 0.61535 0.57247)
			(layers "F.Cu" "F.Mask" "F.Paste")
			(net "RF_IN")
			(solder_mask_margin 0)
			(solder_paste_margin 0)
		)
		(pad "2" smd rect
			(at 0.42856 0 90)
			(size 0.61535 0.57247)
			(layers "F.Cu" "F.Mask" "F.Paste")
			(net "RF_ANT")
			(solder_mask_margin 0)
			(solder_paste_margin 0)
		)
	)
	(footprint "Vault:RESC1005X40X25NL05T10"
		(layer "F.Cu")
		(at 145.601105 117.9036 -90)
		(property "Reference" "R13"
			(at 0.6 -0.800076 90)
			(unlocked yes)
			(layer "F.SilkS")
			(effects
				(font
					(face "Arial")
					(size 0.48006 0.48006)
					(thickness 0.254)
				)
			)
		)
		(property "Value" "0_5%_0402"
			(at -2.385831 6.512925 180)
			(unlocked yes)
			(layer "F.SilkS")
			(hide yes)
			(effects
				(font
					(face "Arial")
					(size 0.96012 0.96012)
					(thickness 0.254)
				)
			)
		)
		(sheetname "03-M2_GoldFingers")
		(sheetfile "03-M2_GoldFingers.kicad_sch")
		(duplicate_pad_numbers_are_jumpers no)
		(fp_line
			(start -0.9 0.45)
			(end -0.9 -0.45)
			(stroke
				(width 0.05)
				(type solid)
			)
			(layer "F.CrtYd")
		)
		(fp_line
			(start 0.9 0.45)
			(end -0.9 0.45)
			(stroke
				(width 0.05)
				(type solid)
			)
			(layer "F.CrtYd")
		)
		(fp_line
			(start 0.9 0.45)
			(end 0.9 -0.45)
			(stroke
				(width 0.05)
				(type solid)
			)
			(layer "F.CrtYd")
		)
		(fp_line
			(start 0 0.275)
			(end 0 -0.275)
			(stroke
				(width 0.1)
				(type solid)
			)
			(layer "F.CrtYd")
		)
		(fp_line
			(start 0.275 0)
			(end -0.275 0)
			(stroke
				(width 0.1)
				(type solid)
			)
			(layer "F.CrtYd")
		)
		(fp_line
			(start 0.9 -0.45)
			(end -0.9 -0.45)
			(stroke
				(width 0.05)
				(type solid)
			)
			(layer "F.CrtYd")
		)
		(pad "1" smd rect
			(at -0.425 0)
			(size 0.55 0.6)
			(layers "F.Cu" "F.Mask" "F.Paste")
			(net "RST_GPS")
		)
		(pad "2" smd rect
			(at 0.425 0)
			(size 0.55 0.6)
			(layers "F.Cu" "F.Mask" "F.Paste")
			(net "NetJ1_50")
		)
	)
	(footprint "Vault:FP-RMCF0402-IPC_C"
		(layer "F.Cu")
		(at 142.901105 90.4036 -90)
		(property "Reference" "R9"
			(at 1.349995 -0.000025 270)
			(unlocked yes)
			(layer "F.SilkS")
			(effects
				(font
					(face "Arial")
					(size 0.40005 0.40005)
					(thickness 0.178)
				)
			)
		)
		(property "Value" "100k"
			(at 6.538115 1.947571 270)
			(unlocked yes)
			(layer "F.SilkS")
			(hide yes)
			(effects
				(font
					(face "Arial")
					(size 0.96012 0.96012)
					(thickness 0.254)
				)
			)
		)
		(sheetname "02-Antenna_Supervisor")
		(sheetfile "02-Antenna_Supervisor.kicad_sch")
		(duplicate_pad_numbers_are_jumpers no)
		(fp_line
			(start -0.75607 0.375)
			(end -0.75607 -0.375)
			(stroke
				(width 0.2)
				(type solid)
			)
			(layer "F.CrtYd")
		)
		(fp_line
			(start 0.75607 0.375)
			(end -0.75607 0.375)
			(stroke
				(width 0.2)
				(type solid)
			)
			(layer "F.CrtYd")
		)
		(fp_line
			(start 0.75607 0.375)
			(end 0.75607 -0.375)
			(stroke
				(width 0.2)
				(type solid)
			)
			(layer "F.CrtYd")
		)
		(fp_line
			(start 0.75607 -0.375)
			(end -0.75607 -0.375)
			(stroke
				(width 0.2)
				(type solid)
			)
			(layer "F.CrtYd")
		)
		(fp_line
			(start 0 0.5)
			(end 0 -0.5)
			(stroke
				(width 0.1)
				(type solid)
			)
			(layer "F.Fab")
		)
		(fp_line
			(start -0.75607 0.375)
			(end -0.75607 -0.375)
			(stroke
				(width 0.2)
				(type solid)
			)
			(layer "F.Fab")
		)
		(fp_line
			(start 0.75607 0.375)
			(end -0.75607 0.375)
			(stroke
				(width 0.2)
				(type solid)
			)
			(layer "F.Fab")
		)
		(fp_line
			(start 0.75607 0.375)
			(end 0.75607 -0.375)
			(stroke
				(width 0.2)
				(type solid)
			)
			(layer "F.Fab")
		)
		(fp_line
			(start 0.5 0)
			(end -0.5 0)
			(stroke
				(width 0.1)
				(type solid)
			)
			(layer "F.Fab")
		)
		(fp_line
			(start 0.75607 -0.375)
			(end -0.75607 -0.375)
			(stroke
				(width 0.2)
				(type solid)
			)
			(layer "F.Fab")
		)
		(fp_text user "${REFERENCE}"
			(at -0.00001 0.09602 270)
			(unlocked yes)
			(layer "F.Fab")
			(effects
				(font
					(face "Arial")
					(size 0.63 0.63)
					(thickness 0.1)
				)
				(justify left bottom)
			)
		)
		(pad "1" smd rect
			(at -0.36554 0 270)
			(size 0.58106 0.47247)
			(layers "F.Cu" "F.Mask" "F.Paste")
			(net "NetQ1_1")
			(solder_mask_margin 0)
			(solder_paste_margin 0)
		)
		(pad "2" smd rect
			(at 0.36554 0 270)
			(size 0.58106 0.47247)
			(layers "F.Cu" "F.Mask" "F.Paste")
			(net "+3V3")
			(solder_mask_margin 0)
			(solder_paste_margin 0)
		)
	)
	(footprint "Vault:FP-LQG15HH_02-IPC_B"
		(layer "F.Cu")
		(at 154.188925 89.52566)
		(property "Reference" "L1"
			(at 1.616665 0.098335 0)
			(unlocked yes)
			(layer "F.SilkS")
			(effects
				(font
					(face "Arial")
					(size 0.40005 0.40005)
					(thickness 0.1778)
				)
			)
		)
		(property "Value" "47nH 300mA"
			(at 12.784545 2.012615 0)
			(unlocked yes)
			(layer "F.SilkS")
			(hide yes)
			(effects
				(font
					(face "Arial")
					(size 0.40005 0.40005)
					(thickness 0.1778)
				)
			)
		)
		(sheetname "02-Antenna_Supervisor")
		(sheetfile "02-Antenna_Supervisor.kicad_sch")
		(duplicate_pad_numbers_are_jumpers no)
		(fp_line
			(start -0.88624 -0.43624)
			(end 0.88624 -0.43624)
			(stroke
				(width 0.2)
				(type solid)
			)
			(layer "F.CrtYd")
		)
		(fp_line
			(start -0.88624 0.43623)
			(end -0.88624 -0.43624)
			(stroke
				(width 0.2)
				(type solid)
			)
			(layer "F.CrtYd")
		)
		(fp_line
			(start -0.88624 0.43623)
			(end 0.88624 0.43623)
			(stroke
				(width 0.2)
				(type solid)
			)
			(layer "F.CrtYd")
		)
		(fp_line
			(start 0.88624 0.43623)
			(end 0.88624 -0.43624)
			(stroke
				(width 0.2)
				(type solid)
			)
			(layer "F.CrtYd")
		)
		(fp_line
			(start -0.88624 -0.43624)
			(end 0.88624 -0.43624)
			(stroke
				(width 0.2)
				(type solid)
			)
			(layer "F.Fab")
		)
		(fp_line
			(start -0.88624 0.43623)
			(end -0.88624 -0.43624)
			(stroke
				(width 0.2)
				(type solid)
			)
			(layer "F.Fab")
		)
		(fp_line
			(start -0.88624 0.43623)
			(end 0.88624 0.43623)
			(stroke
				(width 0.2)
				(type solid)
			)
			(layer "F.Fab")
		)
		(fp_line
			(start -0.5 0)
			(end 0.5 0)
			(stroke
				(width 0.1)
				(type solid)
			)
			(layer "F.Fab")
		)
		(fp_line
			(start 0 0.5)
			(end 0 -0.5)
			(stroke
				(width 0.1)
				(type solid)
			)
			(layer "F.Fab")
		)
		(fp_line
			(start 0.88624 0.43623)
			(end 0.88624 -0.43624)
			(stroke
				(width 0.2)
				(type solid)
			)
			(layer "F.Fab")
		)
		(fp_text user "${REFERENCE}"
			(at 0 0.29534 360)
			(unlocked yes)
			(layer "F.Fab")
			(effects
				(font
					(face "Arial")
					(size 0.63 0.63)
					(thickness 0.1)
				)
				(justify left bottom)
			)
		)
		(pad "1" smd rect
			(at -0.42856 0)
			(size 0.61535 0.57247)
			(layers "F.Cu" "F.Mask" "F.Paste")
			(net "NetC12_1")
			(solder_mask_margin 0)
			(solder_paste_margin 0)
		)
		(pad "2" smd rect
			(at 0.42856 0)
			(size 0.61535 0.57247)
			(layers "F.Cu" "F.Mask" "F.Paste")
			(net "RF_ANT")
			(solder_mask_margin 0)
			(solder_paste_margin 0)
		)
	)
	(footprint "Vault:RESC1005X40X25NL05T10"
		(layer "F.Cu")
		(at 147.901105 118.2036 90)
		(property "Reference" "R15"
			(at 1.7 -0.099924 90)
			(unlocked yes)
			(layer "F.SilkS")
			(effects
				(font
					(face "Arial")
					(size 0.48006 0.48006)
					(thickness 0.254)
				)
			)
		)
		(property "Value" "0_5%_0402"
			(at -2.385841 6.512925 0)
			(unlocked yes)
			(layer "F.SilkS")
			(hide yes)
			(effects
				(font
					(face "Arial")
					(size 0.96012 0.96012)
					(thickness 0.254)
				)
			)
		)
		(sheetname "03-M2_GoldFingers")
		(sheetfile "03-M2_GoldFingers.kicad_sch")
		(duplicate_pad_numbers_are_jumpers no)
		(fp_line
			(start 0.9 -0.45)
			(end 0.9 0.45)
			(stroke
				(width 0.05)
				(type solid)
			)
			(layer "F.CrtYd")
		)
		(fp_line
			(start -0.9 -0.45)
			(end 0.9 -0.45)
			(stroke
				(width 0.05)
				(type solid)
			)
			(layer "F.CrtYd")
		)
		(fp_line
			(start -0.9 -0.45)
			(end -0.9 0.45)
			(stroke
				(width 0.05)
				(type solid)
			)
			(layer "F.CrtYd")
		)
		(fp_line
			(start 0 -0.275)
			(end 0 0.275)
			(stroke
				(width 0.1)
				(type solid)
			)
			(layer "F.CrtYd")
		)
		(fp_line
			(start -0.275 0)
			(end 0.275 0)
			(stroke
				(width 0.1)
				(type solid)
			)
			(layer "F.CrtYd")
		)
		(fp_line
			(start -0.9 0.45)
			(end 0.9 0.45)
			(stroke
				(width 0.05)
				(type solid)
			)
			(layer "F.CrtYd")
		)
		(pad "1" smd rect
			(at -0.425 0 180)
			(size 0.55 0.6)
			(layers "F.Cu" "F.Mask" "F.Paste")
			(net "NetJ1_46")
		)
		(pad "2" smd rect
			(at 0.425 0 180)
			(size 0.55 0.6)
			(layers "F.Cu" "F.Mask" "F.Paste")
			(net "TP1")
		)
	)
	(footprint "Vault:ONSC-SOT-23-3-318-08_V"
		(layer "F.Cu")
		(at 145.101105 90.8036)
		(property "Reference" "Q1"
			(at 2.042805 1.400005 270)
			(unlocked yes)
			(layer "F.SilkS")
			(effects
				(font
					(face "Arial")
					(size 0.40005 0.40005)
					(thickness 0.1778)
				)
			)
		)
		(property "Value" "NTR2101PT1G"
			(at 7.629825 3.173111 0)
			(unlocked yes)
			(layer "F.SilkS")
			(hide yes)
			(effects
				(font
					(face "Arial")
					(size 0.96012 0.96012)
					(thickness 0.254)
				)
			)
		)
		(sheetname "02-Antenna_Supervisor")
		(sheetfile "02-Antenna_Supervisor.kicad_sch")
		(duplicate_pad_numbers_are_jumpers no)
		(fp_line
			(start -0.165 -1.46)
			(end 0.65 -1.46)
			(stroke
				(width 0.2)
				(type solid)
			)
			(layer "F.SilkS")
		)
		(fp_line
			(start -0.165 1.46)
			(end 0.65 1.46)
			(stroke
				(width 0.2)
				(type solid)
			)
			(layer "F.SilkS")
		)
		(fp_line
			(start 0.65 -0.8)
			(end 0.65 -1.46)
			(stroke
				(width 0.2)
				(type solid)
			)
			(layer "F.SilkS")
		)
		(fp_line
			(start 0.65 1.46)
			(end 0.65 0.8)
			(stroke
				(width 0.2)
				(type solid)
			)
			(layer "F.SilkS")
		)
		(fp_circle
			(center -2.05607 -1.477)
			(end -2.05607 -1.602)
			(stroke
				(width 0.25)
				(type solid)
			)
			(fill no)
			(layer "F.SilkS")
		)
		(fp_line
			(start -1.55 -1.56)
			(end 1.55 -1.56)
			(stroke
				(width 0.05)
				(type solid)
			)
			(layer "F.CrtYd")
		)
		(fp_line
			(start -1.55 1.56)
			(end -1.55 -1.56)
			(stroke
				(width 0.05)
				(type solid)
			)
			(layer "F.CrtYd")
		)
		(fp_line
			(start -1.55 1.56)
			(end 1.55 1.56)
			(stroke
				(width 0.05)
				(type solid)
			)
			(layer "F.CrtYd")
		)
		(fp_line
			(start -0.5 0)
			(end 0.5 0)
			(stroke
				(width 0.1)
				(type solid)
			)
			(layer "F.CrtYd")
		)
		(fp_line
			(start 0 0.5)
			(end 0 -0.5)
			(stroke
				(width 0.1)
				(type solid)
			)
			(layer "F.CrtYd")
		)
		(fp_line
			(start 1.55 1.56)
			(end 1.55 -1.56)
			(stroke
				(width 0.05)
				(type solid)
			)
			(layer "F.CrtYd")
		)
		(pad "1" smd rect
			(at -1 -0.95 90)
			(size 0.8 0.9)
			(layers "F.Cu" "F.Mask" "F.Paste")
			(net "NetQ1_1")
		)
		(pad "2" smd rect
			(at -1 0.95 90)
			(size 0.8 0.9)
			(layers "F.Cu" "F.Mask" "F.Paste")
			(net "+3V3")
		)
		(pad "3" smd rect
			(at 1 0 90)
			(size 0.8 0.9)
			(layers "F.Cu" "F.Mask" "F.Paste")
			(net "NetQ1_3")
		)
	)
	(footprint "Vault:FP-RMCF0402-MFG"
		(layer "F.Cu")
		(at 138.601105 91.6036 -90)
		(property "Reference" "R18"
			(at 2.700005 2.898979 90)
			(unlocked yes)
			(layer "F.SilkS")
			(effects
				(font
					(face "Arial")
					(size 0.96012 0.96012)
					(thickness 0.254)
				)
			)
		)
		(property "Value" "1k"
			(at -2.286231 0.46957 180)
			(unlocked yes)
			(layer "F.SilkS")
			(hide yes)
			(effects
				(font
					(face "Arial")
					(size 0.96012 0.96012)
					(thickness 0.254)
				)
			)
		)
		(sheetname "02-Antenna_Supervisor")
		(sheetfile "02-Antenna_Supervisor.kicad_sch")
		(duplicate_pad_numbers_are_jumpers no)
		(fp_line
			(start -0.85 0.4)
			(end -0.85 -0.4)
			(stroke
				(width 0.2)
				(type solid)
			)
			(layer "F.CrtYd")
		)
		(fp_line
			(start 0.85 0.4)
			(end -0.85 0.4)
			(stroke
				(width 0.2)
				(type solid)
			)
			(layer "F.CrtYd")
		)
		(fp_line
			(start 0.85 0.4)
			(end 0.85 -0.4)
			(stroke
				(width 0.2)
				(type solid)
			)
			(layer "F.CrtYd")
		)
		(fp_line
			(start 0.85 -0.4)
			(end -0.85 -0.4)
			(stroke
				(width 0.2)
				(type solid)
			)
			(layer "F.CrtYd")
		)
		(fp_line
			(start 0 0.5)
			(end 0 -0.5)
			(stroke
				(width 0.1)
				(type solid)
			)
			(layer "F.Fab")
		)
		(fp_line
			(start -0.85 0.4)
			(end -0.85 -0.4)
			(stroke
				(width 0.2)
				(type solid)
			)
			(layer "F.Fab")
		)
		(fp_line
			(start 0.85 0.4)
			(end -0.85 0.4)
			(stroke
				(width 0.2)
				(type solid)
			)
			(layer "F.Fab")
		)
		(fp_line
			(start 0.85 0.4)
			(end 0.85 -0.4)
			(stroke
				(width 0.2)
				(type solid)
			)
			(layer "F.Fab")
		)
		(fp_line
			(start 0.5 0)
			(end -0.5 0)
			(stroke
				(width 0.1)
				(type solid)
			)
			(layer "F.Fab")
		)
		(fp_line
			(start 0.85 -0.4)
			(end -0.85 -0.4)
			(stroke
				(width 0.2)
				(type solid)
			)
			(layer "F.Fab")
		)
		(fp_text user "${REFERENCE}"
			(at -0.00001 0.09602 270)
			(unlocked yes)
			(layer "F.Fab")
			(effects
				(font
					(face "Arial")
					(size 0.63 0.63)
					(thickness 0.1)
				)
				(justify left bottom)
			)
		)
		(pad "1" smd rect
			(at -0.5 0 270)
			(size 0.5 0.6)
			(layers "F.Cu" "F.Mask" "F.Paste")
			(net "ANT_SHORT_N")
			(solder_mask_margin 0)
			(solder_paste_margin 0)
		)
		(pad "2" smd rect
			(at 0.5 0 270)
			(size 0.5 0.6)
			(layers "F.Cu" "F.Mask" "F.Paste")
			(net "+3V3")
			(solder_mask_margin 0)
			(solder_paste_margin 0)
		)
	)
	(footprint "Vault:FP-LTST-C191KGKT-MFG"
		(layer "F.Cu")
		(at 140.038955 114.27079)
		(property "Reference" "D3"
			(at -0.03785 1.333831 0)
			(unlocked yes)
			(layer "F.SilkS")
			(effects
				(font
					(face "Arial")
					(size 0.96012 0.96012)
					(thickness 0.254)
				)
			)
		)
		(property "Value" "LTST-C191KGKT"
			(at 7.705855 2.207911 0)
			(unlocked yes)
			(layer "F.SilkS")
			(hide yes)
			(effects
				(font
					(face "Arial")
					(size 0.96012 0.96012)
					(thickness 0.254)
				)
			)
		)
		(sheetname "01-M2_ZED-F9T_MODULE")
		(sheetfile "01-M2_ZED-F9T_MODULE.kicad_sch")
		(duplicate_pad_numbers_are_jumpers no)
		(fp_line
			(start -0.85001 -0.775)
			(end 0.85 -0.775)
			(stroke
				(width 0.2)
				(type solid)
			)
			(layer "F.SilkS")
		)
		(fp_line
			(start -0.85001 0.775)
			(end 0.85 0.775)
			(stroke
				(width 0.2)
				(type solid)
			)
			(layer "F.SilkS")
		)
		(fp_circle
			(center -1.7 0)
			(end -1.7 -0.125)
			(stroke
				(width 0.25)
				(type solid)
			)
			(fill no)
			(layer "F.SilkS")
		)
		(fp_line
			(start -1.25 -0.55)
			(end 1.25 -0.55)
			(stroke
				(width 0.2)
				(type solid)
			)
			(layer "F.CrtYd")
		)
		(fp_line
			(start -1.25 0.55)
			(end -1.25 -0.55)
			(stroke
				(width 0.2)
				(type solid)
			)
			(layer "F.CrtYd")
		)
		(fp_line
			(start -1.25 0.55)
			(end 1.25 0.55)
			(stroke
				(width 0.2)
				(type solid)
			)
			(layer "F.CrtYd")
		)
		(fp_line
			(start 1.25 0.55)
			(end 1.25 -0.55)
			(stroke
				(width 0.2)
				(type solid)
			)
			(layer "F.CrtYd")
		)
		(fp_line
			(start -1.25 -0.55)
			(end 1.25 -0.55)
			(stroke
				(width 0.2)
				(type solid)
			)
			(layer "F.Fab")
		)
		(fp_line
			(start -1.25 0.55)
			(end -1.25 -0.55)
			(stroke
				(width 0.2)
				(type solid)
			)
			(layer "F.Fab")
		)
		(fp_line
			(start -1.25 0.55)
			(end 1.25 0.55)
			(stroke
				(width 0.2)
				(type solid)
			)
			(layer "F.Fab")
		)
		(fp_line
			(start -0.5 0)
			(end 0.49999 0)
			(stroke
				(width 0.1)
				(type solid)
			)
			(layer "F.Fab")
		)
		(fp_line
			(start 0 0.5)
			(end 0 -0.5)
			(stroke
				(width 0.1)
				(type solid)
			)
			(layer "F.Fab")
		)
		(fp_line
			(start 1.25 0.55)
			(end 1.25 -0.55)
			(stroke
				(width 0.2)
				(type solid)
			)
			(layer "F.Fab")
		)
		(fp_text user "${REFERENCE}"
			(at 0 0.28425 360)
			(unlocked yes)
			(layer "F.Fab")
			(effects
				(font
					(face "Arial")
					(size 0.63 0.63)
					(thickness 0.1)
				)
				(justify left bottom)
			)
		)
		(pad "1" smd rect
			(at -0.75001 0)
			(size 0.8 0.8)
			(layers "F.Cu" "F.Mask" "F.Paste")
			(net "NetD3_1")
			(solder_mask_margin 0)
			(solder_paste_margin 0)
		)
		(pad "2" smd rect
			(at 0.75 0)
			(size 0.8 0.8)
			(layers "F.Cu" "F.Mask" "F.Paste")
			(net "+3V3")
			(solder_mask_margin 0)
			(solder_paste_margin 0)
		)
	)
	(footprint "Vault:FP-CL542-IPC_C"
		(layer "F.Cu")
		(at 143.901105 113.3036)
		(property "Reference" "C5"
			(at -1.3 -0.455485 0)
			(unlocked yes)
			(layer "F.SilkS")
			(effects
				(font
					(face "Arial")
					(size 0.40005 0.40005)
					(thickness 0.1778)
				)
			)
		)
		(property "Value" "1uF_25V_0402"
			(at 4.88765 1.959815 0)
			(unlocked yes)
			(layer "F.SilkS")
			(hide yes)
			(effects
				(font
					(face "Arial")
					(size 0.40005 0.40005)
					(thickness 0.1778)
				)
			)
		)
		(sheetname "01-M2_ZED-F9T_MODULE")
		(sheetfile "01-M2_ZED-F9T_MODULE.kicad_sch")
		(duplicate_pad_numbers_are_jumpers no)
		(fp_line
			(start -0.63624 -0.675)
			(end 0.63624 -0.675)
			(stroke
				(width 0.2)
				(type solid)
			)
			(layer "F.SilkS")
		)
		(fp_line
			(start -0.63624 0.675)
			(end 0.63624 0.675)
			(stroke
				(width 0.2)
				(type solid)
			)
			(layer "F.SilkS")
		)
		(fp_line
			(start -0.73624 -0.375)
			(end 0.73624 -0.375)
			(stroke
				(width 0.2)
				(type solid)
			)
			(layer "F.CrtYd")
		)
		(fp_line
			(start -0.73624 0.375)
			(end -0.73624 -0.375)
			(stroke
				(width 0.2)
				(type solid)
			)
			(layer "F.CrtYd")
		)
		(fp_line
			(start -0.73624 0.375)
			(end 0.73624 0.375)
			(stroke
				(width 0.2)
				(type solid)
			)
			(layer "F.CrtYd")
		)
		(fp_line
			(start 0.73624 0.375)
			(end 0.73624 -0.375)
			(stroke
				(width 0.2)
				(type solid)
			)
			(layer "F.CrtYd")
		)
		(fp_line
			(start -0.73624 -0.375)
			(end 0.73624 -0.375)
			(stroke
				(width 0.2)
				(type solid)
			)
			(layer "F.Fab")
		)
		(fp_line
			(start -0.73624 0.375)
			(end -0.73624 -0.375)
			(stroke
				(width 0.2)
				(type solid)
			)
			(layer "F.Fab")
		)
		(fp_line
			(start -0.73624 0.375)
			(end 0.73624 0.375)
			(stroke
				(width 0.2)
				(type solid)
			)
			(layer "F.Fab")
		)
		(fp_line
			(start -0.5 0)
			(end 0.5 0)
			(stroke
				(width 0.1)
				(type solid)
			)
			(layer "F.Fab")
		)
		(fp_line
			(start -0.5 0)
			(end 0.5 0)
			(stroke
				(width 0.1)
				(type solid)
			)
			(layer "F.Fab")
		)
		(fp_line
			(start 0 0.5)
			(end 0 -0.5)
			(stroke
				(width 0.1)
				(type solid)
			)
			(layer "F.Fab")
		)
		(fp_line
			(start 0 0.5)
			(end 0 -0.5)
			(stroke
				(width 0.1)
				(type solid)
			)
			(layer "F.Fab")
		)
		(fp_line
			(start 0.73624 0.375)
			(end 0.73624 -0.375)
			(stroke
				(width 0.2)
				(type solid)
			)
			(layer "F.Fab")
		)
		(fp_text user "${REFERENCE}"
			(at 0 0.28425 360)
			(unlocked yes)
			(layer "F.Fab")
			(effects
				(font
					(face "Arial")
					(size 0.63 0.63)
					(thickness 0.1)
				)
				(justify left bottom)
			)
		)
		(pad "1" smd rect
			(at -0.37856 0)
			(size 0.51535 0.47247)
			(layers "F.Cu" "F.Mask" "F.Paste")
			(net "GND")
			(solder_mask_margin 0)
			(solder_paste_margin 0)
		)
		(pad "2" smd rect
			(at 0.37856 0)
			(size 0.51535 0.47247)
			(layers "F.Cu" "F.Mask" "F.Paste")
			(net "NetC5_2")
			(solder_mask_margin 0)
			(solder_paste_margin 0)
		)
	)
	(footprint "Vault:FP-GRM31C-0_2-e0_3_0_8-IPC_C"
		(layer "F.Cu")
		(at 157.701105 119.6036 90)
		(property "Reference" "C6"
			(at 2.596754 0.6 0)
			(unlocked yes)
			(layer "F.SilkS")
			(effects
				(font
					(face "Arial")
					(size 0.48006 0.48006)
					(thickness 0.254)
				)
			)
		)
		(property "Value" "47uF_6.3V_1206"
			(at 8.366015 2.430251 90)
			(unlocked yes)
			(layer "F.SilkS")
			(hide yes)
			(effects
				(font
					(face "Arial")
					(size 0.96012 0.96012)
					(thickness 0.254)
				)
			)
		)
		(sheetname "03-M2_GoldFingers")
		(sheetfile "03-M2_GoldFingers.kicad_sch")
		(duplicate_pad_numbers_are_jumpers no)
		(fp_line
			(start -0.39847 -0.9)
			(end 0.39846 -0.9)
			(stroke
				(width 0.2)
				(type solid)
			)
			(layer "F.SilkS")
		)
		(fp_line
			(start -0.39847 0.9)
			(end 0.39846 0.9)
			(stroke
				(width 0.2)
				(type solid)
			)
			(layer "F.SilkS")
		)
		(fp_line
			(start 1.9531 -1)
			(end 1.9531 1)
			(stroke
				(width 0.2)
				(type solid)
			)
			(layer "F.CrtYd")
		)
		(fp_line
			(start -1.9531 -1)
			(end 1.9531 -1)
			(stroke
				(width 0.2)
				(type solid)
			)
			(layer "F.CrtYd")
		)
		(fp_line
			(start -1.9531 -1)
			(end -1.9531 1)
			(stroke
				(width 0.2)
				(type solid)
			)
			(layer "F.CrtYd")
		)
		(fp_line
			(start -1.9531 1)
			(end 1.9531 1)
			(stroke
				(width 0.2)
				(type solid)
			)
			(layer "F.CrtYd")
		)
		(fp_line
			(start 1.9531 -1)
			(end 1.9531 1)
			(stroke
				(width 0.2)
				(type solid)
			)
			(layer "F.Fab")
		)
		(fp_line
			(start -1.9531 -1)
			(end 1.9531 -1)
			(stroke
				(width 0.2)
				(type solid)
			)
			(layer "F.Fab")
		)
		(fp_line
			(start -1.9531 -1)
			(end -1.9531 1)
			(stroke
				(width 0.2)
				(type solid)
			)
			(layer "F.Fab")
		)
		(fp_line
			(start 0 -0.5)
			(end 0 0.5)
			(stroke
				(width 0.1)
				(type solid)
			)
			(layer "F.Fab")
		)
		(fp_line
			(start -0.5 0)
			(end 0.5 0)
			(stroke
				(width 0.1)
				(type solid)
			)
			(layer "F.Fab")
		)
		(fp_line
			(start -1.9531 1)
			(end 1.9531 1)
			(stroke
				(width 0.2)
				(type solid)
			)
			(layer "F.Fab")
		)
		(fp_text user "${REFERENCE}"
			(at -0.00002 0.09602 90)
			(unlocked yes)
			(layer "F.Fab")
			(effects
				(font
					(face "Arial")
					(size 0.63 0.63)
					(thickness 0.1)
				)
				(justify left bottom)
			)
		)
		(pad "1" smd rect
			(at -1.27578 0 90)
			(size 1.15464 1.7062)
			(layers "F.Cu" "F.Mask" "F.Paste")
			(net "+3V3")
			(solder_mask_margin 0)
			(solder_paste_margin 0)
		)
		(pad "2" smd rect
			(at 1.27578 0 90)
			(size 1.15464 1.7062)
			(layers "F.Cu" "F.Mask" "F.Paste")
			(net "GND")
			(solder_mask_margin 0)
			(solder_paste_margin 0)
		)
	)
	(footprint "Vault:FP-CL542-IPC_C"
		(layer "F.Cu")
		(at 150.701105 110.5036)
		(property "Reference" "C3"
			(at 1.302655 -0.080485 0)
			(unlocked yes)
			(layer "F.SilkS")
			(effects
				(font
					(face "Arial")
					(size 0.40005 0.40005)
					(thickness 0.1778)
				)
			)
		)
		(property "Value" "1uF_25V_0402"
			(at 4.88765 1.959815 0)
			(unlocked yes)
			(layer "F.SilkS")
			(hide yes)
			(effects
				(font
					(face "Arial")
					(size 0.40005 0.40005)
					(thickness 0.1778)
				)
			)
		)
		(sheetname "01-M2_ZED-F9T_MODULE")
		(sheetfile "01-M2_ZED-F9T_MODULE.kicad_sch")
		(duplicate_pad_numbers_are_jumpers no)
		(fp_line
			(start -0.73624 -0.375)
			(end 0.73624 -0.375)
			(stroke
				(width 0.2)
				(type solid)
			)
			(layer "F.CrtYd")
		)
		(fp_line
			(start -0.73624 0.375)
			(end -0.73624 -0.375)
			(stroke
				(width 0.2)
				(type solid)
			)
			(layer "F.CrtYd")
		)
		(fp_line
			(start -0.73624 0.375)
			(end 0.73624 0.375)
			(stroke
				(width 0.2)
				(type solid)
			)
			(layer "F.CrtYd")
		)
		(fp_line
			(start 0.73624 0.375)
			(end 0.73624 -0.375)
			(stroke
				(width 0.2)
				(type solid)
			)
			(layer "F.CrtYd")
		)
		(fp_line
			(start -0.73624 -0.375)
			(end 0.73624 -0.375)
			(stroke
				(width 0.2)
				(type solid)
			)
			(layer "F.Fab")
		)
		(fp_line
			(start -0.73624 0.375)
			(end -0.73624 -0.375)
			(stroke
				(width 0.2)
				(type solid)
			)
			(layer "F.Fab")
		)
		(fp_line
			(start -0.73624 0.375)
			(end 0.73624 0.375)
			(stroke
				(width 0.2)
				(type solid)
			)
			(layer "F.Fab")
		)
		(fp_line
			(start -0.5 0)
			(end 0.5 0)
			(stroke
				(width 0.1)
				(type solid)
			)
			(layer "F.Fab")
		)
		(fp_line
			(start -0.5 0)
			(end 0.5 0)
			(stroke
				(width 0.1)
				(type solid)
			)
			(layer "F.Fab")
		)
		(fp_line
			(start 0 0.5)
			(end 0 -0.5)
			(stroke
				(width 0.1)
				(type solid)
			)
			(layer "F.Fab")
		)
		(fp_line
			(start 0 0.5)
			(end 0 -0.5)
			(stroke
				(width 0.1)
				(type solid)
			)
			(layer "F.Fab")
		)
		(fp_line
			(start 0.73624 0.375)
			(end 0.73624 -0.375)
			(stroke
				(width 0.2)
				(type solid)
			)
			(layer "F.Fab")
		)
		(fp_text user "${REFERENCE}"
			(at 0 0.28425 360)
			(unlocked yes)
			(layer "F.Fab")
			(effects
				(font
					(face "Arial")
					(size 0.63 0.63)
					(thickness 0.1)
				)
				(justify left bottom)
			)
		)
		(pad "1" smd rect
			(at -0.37856 0)
			(size 0.51535 0.47247)
			(layers "F.Cu" "F.Mask" "F.Paste")
			(net "+3V3")
			(solder_mask_margin 0)
			(solder_paste_margin 0)
		)
		(pad "2" smd rect
			(at 0.37856 0)
			(size 0.51535 0.47247)
			(layers "F.Cu" "F.Mask" "F.Paste")
			(net "GND")
			(solder_mask_margin 0)
			(solder_paste_margin 0)
		)
	)
	(footprint "Vault:DCU0008A_N"
		(layer "F.Cu")
		(at 139.601105 88.4036 -90)
		(property "Reference" "U3"
			(at -0.000005 1.798979 90)
			(unlocked yes)
			(layer "F.SilkS")
			(effects
				(font
					(face "Arial")
					(size 0.96012 0.96012)
					(thickness 0.254)
				)
			)
		)
		(property "Value" "SN74LVC3G07DCUR"
			(at 9.17849 2.665111 270)
			(unlocked yes)
			(layer "F.SilkS")
			(hide yes)
			(effects
				(font
					(face "Arial")
					(size 0.96012 0.96012)
					(thickness 0.254)
				)
			)
		)
		(sheetname "02-Antenna_Supervisor")
		(sheetfile "02-Antenna_Supervisor.kicad_sch")
		(duplicate_pad_numbers_are_jumpers no)
		(fp_line
			(start -0.8 1.05)
			(end -0.8 -1.05)
			(stroke
				(width 0.2)
				(type solid)
			)
			(layer "F.SilkS")
		)
		(fp_line
			(start 0.8 1.05)
			(end -0.8 1.05)
			(stroke
				(width 0.2)
				(type solid)
			)
			(layer "F.SilkS")
		)
		(fp_line
			(start 0.8 1.05)
			(end 0.8 -1.05)
			(stroke
				(width 0.2)
				(type solid)
			)
			(layer "F.SilkS")
		)
		(fp_line
			(start 0.8 -1.05)
			(end -0.8 -1.05)
			(stroke
				(width 0.2)
				(type solid)
			)
			(layer "F.SilkS")
		)
		(fp_circle
			(center -1.6 -1.45)
			(end -1.725 -1.45)
			(stroke
				(width 0.25)
				(type solid)
			)
			(fill no)
			(layer "F.SilkS")
		)
		(fp_line
			(start -2.225 1.3)
			(end -2.225 -1.3)
			(stroke
				(width 0.05)
				(type solid)
			)
			(layer "F.CrtYd")
		)
		(fp_line
			(start 2.225 1.3)
			(end -2.225 1.3)
			(stroke
				(width 0.05)
				(type solid)
			)
			(layer "F.CrtYd")
		)
		(fp_line
			(start 2.225 1.3)
			(end 2.225 -1.3)
			(stroke
				(width 0.05)
				(type solid)
			)
			(layer "F.CrtYd")
		)
		(fp_line
			(start 0 0.5)
			(end 0 -0.5)
			(stroke
				(width 0.1)
				(type solid)
			)
			(layer "F.CrtYd")
		)
		(fp_line
			(start 0.5 0)
			(end -0.5 0)
			(stroke
				(width 0.1)
				(type solid)
			)
			(layer "F.CrtYd")
		)
		(fp_line
			(start 2.225 -1.3)
			(end -2.225 -1.3)
			(stroke
				(width 0.05)
				(type solid)
			)
			(layer "F.CrtYd")
		)
		(pad "1" smd roundrect
			(at -1.6 -0.75)
			(size 0.3 0.8)
			(layers "F.Cu" "F.Mask" "F.Paste")
			(roundrect_rratio 0.165)
			(net "NetU3_1")
		)
		(pad "2" smd roundrect
			(at -1.6 -0.25)
			(size 0.3 0.8)
			(layers "F.Cu" "F.Mask" "F.Paste")
			(roundrect_rratio 0.165)
			(net "NetQ1_1")
		)
		(pad "3" smd roundrect
			(at -1.6 0.25)
			(size 0.3 0.8)
			(layers "F.Cu" "F.Mask" "F.Paste")
			(roundrect_rratio 0.165)
			(net "NetC12_1")
		)
		(pad "4" smd roundrect
			(at -1.6 0.75)
			(size 0.3 0.8)
			(layers "F.Cu" "F.Mask" "F.Paste")
			(roundrect_rratio 0.165)
			(net "GND")
		)
		(pad "5" smd roundrect
			(at 1.6 0.75)
			(size 0.3 0.8)
			(layers "F.Cu" "F.Mask" "F.Paste")
			(roundrect_rratio 0.165)
			(net "ANT_SHORT_N")
		)
		(pad "6" smd roundrect
			(at 1.6 0.25)
			(size 0.3 0.8)
			(layers "F.Cu" "F.Mask" "F.Paste")
			(roundrect_rratio 0.165)
			(net "ANT_OFF")
		)
		(pad "7" smd roundrect
			(at 1.6 -0.25)
			(size 0.3 0.8)
			(layers "F.Cu" "F.Mask" "F.Paste")
			(roundrect_rratio 0.165)
			(net "ANT_DET")
		)
		(pad "8" smd roundrect
			(at 1.6 -0.75)
			(size 0.3 0.8)
			(layers "F.Cu" "F.Mask" "F.Paste")
			(roundrect_rratio 0.165)
			(net "+3V3")
		)
	)
	(footprint "M2_Library:OCPTAP M2 FINGERS"
		(locked yes)
		(layer "F.Cu")
		(at 157.751105 124.7286)
		(property "Reference" "J1"
			(at -0.92017 -2.308125 0)
			(unlocked yes)
			(layer "F.SilkS")
			(effects
				(font
					(face "Arial")
					(size 0.40005 0.40005)
					(thickness 0.1778)
				)
			)
		)
		(property "Value" "OCPTAP_M2_FINGERS"
			(at 7.73093 8.439455 0)
			(unlocked yes)
			(layer "F.SilkS")
			(hide yes)
			(effects
				(font
					(face "Arial")
					(size 0.40005 0.40005)
					(thickness 0.1778)
				)
			)
		)
		(sheetname "03-M2_GoldFingers")
		(sheetfile "03-M2_GoldFingers.kicad_sch")
		(duplicate_pad_numbers_are_jumpers no)
		(fp_text user "75"
			(at -18.898 -1.525 270)
			(unlocked yes)
			(layer "F.SilkS")
			(effects
				(font
					(face "Arial")
					(size 0.315 0.315)
					(thickness 0.1)
				)
				(justify left bottom mirror)
			)
		)
		(fp_text user "21"
			(at -5.22855 -1.44955 270)
			(unlocked yes)
			(layer "F.SilkS")
			(effects
				(font
					(face "Arial")
					(size 0.315 0.315)
					(thickness 0.1)
				)
				(justify left bottom mirror)
			)
		)
		(fp_text user "11"
			(at -2.70871 -1.425 270)
			(unlocked yes)
			(layer "F.SilkS")
			(effects
				(font
					(face "Arial")
					(size 0.315 0.315)
					(thickness 0.1)
				)
				(justify left bottom mirror)
			)
		)
		(fp_text user "1"
			(at -0.29755 -1.375 270)
			(unlocked yes)
			(layer "F.SilkS")
			(effects
				(font
					(face "Arial")
					(size 0.315 0.315)
					(thickness 0.1)
				)
				(justify left bottom mirror)
			)
		)
		(fp_text user "74"
			(at -18.61125 -1.625 270)
			(unlocked yes)
			(layer "B.SilkS")
			(effects
				(font
					(size 0.5 0.5)
					(thickness 0.1)
				)
				(justify left bottom mirror)
			)
		)
		(fp_text user "20"
			(at -5.21125 -1.425 270)
			(unlocked yes)
			(layer "B.SilkS")
			(effects
				(font
					(size 0.5 0.5)
					(thickness 0.1)
				)
				(justify left bottom mirror)
			)
		)
		(fp_text user "10"
			(at -2.58039 -1.525 270)
			(unlocked yes)
			(layer "B.SilkS")
			(effects
				(font
					(size 0.5 0.5)
					(thickness 0.1)
				)
				(justify left bottom mirror)
			)
		)
		(fp_text user "2"
			(at -0.27841 -1.725 270)
			(unlocked yes)
			(layer "B.SilkS")
			(effects
				(font
					(size 0.5 0.5)
					(thickness 0.1)
				)
				(justify left bottom mirror)
			)
		)
		(pad "1" smd rect
			(at 0 0)
			(size 0.35 1.45)
			(layers "F.Cu" "F.Mask" "F.Paste")
		)
		(pad "2" smd rect
			(at -0.244 -0.25)
			(size 0.35 1.95)
			(layers "B.Cu" "B.Mask" "B.Paste")
			(net "+3V3")
		)
		(pad "3" smd rect
			(at -0.5 0)
			(size 0.35 1.45)
			(layers "F.Cu" "F.Mask" "F.Paste")
			(net "GND")
		)
		(pad "4" smd rect
			(at -0.744 -0.25)
			(size 0.35 1.95)
			(layers "B.Cu" "B.Mask" "B.Paste")
			(net "+3V3")
		)
		(pad "5" smd rect
			(at -1 0)
			(size 0.35 1.45)
			(layers "F.Cu" "F.Mask" "F.Paste")
			(net "GND")
		)
		(pad "6" smd rect
			(at -1.244 -0.25)
			(size 0.35 1.95)
			(layers "B.Cu" "B.Mask" "B.Paste")
		)
		(pad "7" smd rect
			(at -1.5 0)
			(size 0.35 1.45)
			(layers "F.Cu" "F.Mask" "F.Paste")
			(net "USB_D_P")
		)
		(pad "8" smd rect
			(at -1.744 -0.25)
			(size 0.35 1.95)
			(layers "B.Cu" "B.Mask" "B.Paste")
		)
		(pad "9" smd rect
			(at -2 0)
			(size 0.35 1.45)
			(layers "F.Cu" "F.Mask" "F.Paste")
			(net "USB_D_N")
		)
		(pad "10" smd rect
			(at -2.244 -0.25)
			(size 0.35 1.95)
			(layers "B.Cu" "B.Mask" "B.Paste")
		)
		(pad "11" smd rect
			(at -2.5 0)
			(size 0.35 1.45)
			(layers "F.Cu" "F.Mask" "F.Paste")
			(net "GND")
		)
		(pad "20" smd rect
			(at -4.744 -0.25)
			(size 0.35 1.95)
			(layers "B.Cu" "B.Mask" "B.Paste")
		)
		(pad "21" smd rect
			(at -5 0)
			(size 0.35 1.45)
			(layers "F.Cu" "F.Mask" "F.Paste")
			(net "GND")
		)
		(pad "22" smd rect
			(at -5.244 -0.25)
			(size 0.35 1.95)
			(layers "B.Cu" "B.Mask" "B.Paste")
		)
		(pad "23" smd rect
			(at -5.5 0)
			(size 0.35 1.45)
			(layers "F.Cu" "F.Mask" "F.Paste")
		)
		(pad "24" smd rect
			(at -5.744 -0.25)
			(size 0.35 1.95)
			(layers "B.Cu" "B.Mask" "B.Paste")
		)
		(pad "25" smd rect
			(at -6 0)
			(size 0.35 1.45)
			(layers "F.Cu" "F.Mask" "F.Paste")
		)
		(pad "26" smd rect
			(at -6.244 -0.25)
			(size 0.35 1.95)
			(layers "B.Cu" "B.Mask" "B.Paste")
		)
		(pad "27" smd rect
			(at -6.5 0)
			(size 0.35 1.45)
			(layers "F.Cu" "F.Mask" "F.Paste")
			(net "GND")
		)
		(pad "28" smd rect
			(at -6.744 -0.25)
			(size 0.35 1.95)
			(layers "B.Cu" "B.Mask" "B.Paste")
		)
		(pad "29" smd rect
			(at -7 0)
			(size 0.35 1.45)
			(layers "F.Cu" "F.Mask" "F.Paste")
		)
		(pad "30" smd rect
			(at -7.244 -0.25)
			(size 0.35 1.95)
			(layers "B.Cu" "B.Mask" "B.Paste")
		)
		(pad "31" smd rect
			(at -7.5 0)
			(size 0.35 1.45)
			(layers "F.Cu" "F.Mask" "F.Paste")
		)
		(pad "32" smd rect
			(at -7.744 -0.25)
			(size 0.35 1.95)
			(layers "B.Cu" "B.Mask" "B.Paste")
		)
		(pad "33" smd rect
			(at -8 0)
			(size 0.35 1.45)
			(layers "F.Cu" "F.Mask" "F.Paste")
			(net "GND")
		)
		(pad "34" smd rect
			(at -8.244 -0.25)
			(size 0.35 1.95)
			(layers "B.Cu" "B.Mask" "B.Paste")
		)
		(pad "35" smd rect
			(at -8.5 0)
			(size 0.35 1.45)
			(layers "F.Cu" "F.Mask" "F.Paste")
			(net "NetJ1_35")
		)
		(pad "36" smd rect
			(at -8.744 -0.25)
			(size 0.35 1.95)
			(layers "B.Cu" "B.Mask" "B.Paste")
		)
		(pad "37" smd rect
			(at -9 0)
			(size 0.35 1.45)
			(layers "F.Cu" "F.Mask" "F.Paste")
		)
		(pad "38" smd rect
			(at -9.244 -0.25)
			(size 0.35 1.95)
			(layers "B.Cu" "B.Mask" "B.Paste")
		)
		(pad "39" smd rect
			(at -9.5 0)
			(size 0.35 1.45)
			(layers "F.Cu" "F.Mask" "F.Paste")
			(net "GND")
		)
		(pad "40" smd rect
			(at -9.744 -0.25)
			(size 0.35 1.95)
			(layers "B.Cu" "B.Mask" "B.Paste")
			(net "SCL")
		)
		(pad "41" smd rect
			(at -10 0)
			(size 0.35 1.45)
			(layers "F.Cu" "F.Mask" "F.Paste")
		)
		(pad "42" smd rect
			(at -10.244 -0.25)
			(size 0.35 1.95)
			(layers "B.Cu" "B.Mask" "B.Paste")
			(net "SDA")
		)
		(pad "43" smd rect
			(at -10.5 0)
			(size 0.35 1.45)
			(layers "F.Cu" "F.Mask" "F.Paste")
		)
		(pad "44" smd rect
			(at -10.744 -0.25)
			(size 0.35 1.95)
			(layers "B.Cu" "B.Mask" "B.Paste")
		)
		(pad "45" smd rect
			(at -11 0)
			(size 0.35 1.45)
			(layers "F.Cu" "F.Mask" "F.Paste")
			(net "GND")
		)
		(pad "46" smd rect
			(at -11.244 -0.25)
			(size 0.35 1.95)
			(layers "B.Cu" "B.Mask" "B.Paste")
			(net "NetJ1_46")
		)
		(pad "47" smd rect
			(at -11.5 0)
			(size 0.35 1.45)
			(layers "F.Cu" "F.Mask" "F.Paste")
		)
		(pad "48" smd rect
			(at -11.744 -0.25)
			(size 0.35 1.95)
			(layers "B.Cu" "B.Mask" "B.Paste")
		)
		(pad "49" smd rect
			(at -12 0)
			(size 0.35 1.45)
			(layers "F.Cu" "F.Mask" "F.Paste")
		)
		(pad "50" smd rect
			(at -12.244 -0.25)
			(size 0.35 1.95)
			(layers "B.Cu" "B.Mask" "B.Paste")
			(net "NetJ1_50")
		)
		(pad "51" smd rect
			(at -12.5 0)
			(size 0.35 1.45)
			(layers "F.Cu" "F.Mask" "F.Paste")
			(net "GND")
		)
		(pad "52" smd rect
			(at -12.744 -0.25)
			(size 0.35 1.95)
			(layers "B.Cu" "B.Mask" "B.Paste")
		)
		(pad "53" smd rect
			(at -13 0)
			(size 0.35 1.45)
			(layers "F.Cu" "F.Mask" "F.Paste")
		)
		(pad "54" smd rect
			(at -13.244 -0.25)
			(size 0.35 1.95)
			(layers "B.Cu" "B.Mask" "B.Paste")
		)
		(pad "55" smd rect
			(at -13.5 0)
			(size 0.35 1.45)
			(layers "F.Cu" "F.Mask" "F.Paste")
		)
		(pad "56" smd rect
			(at -13.744 -0.25)
			(size 0.35 1.95)
			(layers "B.Cu" "B.Mask" "B.Paste")
		)
		(pad "57" smd rect
			(at -14 0)
			(size 0.35 1.45)
			(layers "F.Cu" "F.Mask" "F.Paste")
			(net "GND")
		)
		(pad "58" smd rect
			(at -14.244 -0.25)
			(size 0.35 1.95)
			(layers "B.Cu" "B.Mask" "B.Paste")
		)
		(pad "59" smd rect
			(at -14.5 0)
			(size 0.35 1.45)
			(layers "F.Cu" "F.Mask" "F.Paste")
		)
		(pad "60" smd rect
			(at -14.744 -0.25)
			(size 0.35 1.95)
			(layers "B.Cu" "B.Mask" "B.Paste")
		)
		(pad "61" smd rect
			(at -15 0)
			(size 0.35 1.45)
			(layers "F.Cu" "F.Mask" "F.Paste")
		)
		(pad "62" smd rect
			(at -15.244 -0.25)
			(size 0.35 1.95)
			(layers "B.Cu" "B.Mask" "B.Paste")
			(net "RX_GPS_CONN")
		)
		(pad "63" smd rect
			(at -15.5 0)
			(size 0.35 1.45)
			(layers "F.Cu" "F.Mask" "F.Paste")
		)
		(pad "64" smd rect
			(at -15.744 -0.25)
			(size 0.35 1.95)
			(layers "B.Cu" "B.Mask" "B.Paste")
			(net "TX_GPS_CONN")
		)
		(pad "65" smd rect
			(at -16 0)
			(size 0.35 1.45)
			(layers "F.Cu" "F.Mask" "F.Paste")
		)
		(pad "66" smd rect
			(at -16.244 -0.25)
			(size 0.35 1.95)
			(layers "B.Cu" "B.Mask" "B.Paste")
		)
		(pad "67" smd rect
			(at -16.5 0)
			(size 0.35 1.45)
			(layers "F.Cu" "F.Mask" "F.Paste")
			(net "NetJ1_67")
		)
		(pad "68" smd rect
			(at -16.744 -0.25)
			(size 0.35 1.95)
			(layers "B.Cu" "B.Mask" "B.Paste")
		)
		(pad "69" smd rect
			(at -17 0)
			(size 0.35 1.45)
			(layers "F.Cu" "F.Mask" "F.Paste")
		)
		(pad "70" smd rect
			(at -17.244 -0.25)
			(size 0.35 1.95)
			(layers "B.Cu" "B.Mask" "B.Paste")
			(net "+3V3")
		)
		(pad "71" smd rect
			(at -17.5 0)
			(size 0.35 1.45)
			(layers "F.Cu" "F.Mask" "F.Paste")
			(net "GND")
		)
		(pad "72" smd rect
			(at -17.744 -0.25)
			(size 0.35 1.95)
			(layers "B.Cu" "B.Mask" "B.Paste")
			(net "+3V3")
		)
		(pad "73" smd rect
			(at -18 0)
			(size 0.35 1.45)
			(layers "F.Cu" "F.Mask" "F.Paste")
			(net "GND")
		)
		(pad "74" smd rect
			(at -18.244 -0.25)
			(size 0.35 1.95)
			(layers "B.Cu" "B.Mask" "B.Paste")
			(net "+3V3")
		)
		(pad "75" smd rect
			(at -18.5 0)
			(size 0.35 1.45)
			(layers "F.Cu" "F.Mask" "F.Paste")
			(net "GND")
		)
	)
	(footprint "Vault:RESC1005X40X25NL05T10"
		(layer "F.Cu")
		(at 145.401105 115.9036 180)
		(property "Reference" "R3"
			(at 2.1 -0.016875 0)
			(unlocked yes)
			(layer "F.SilkS")
			(effects
				(font
					(face "Arial")
					(size 0.40005 0.40005)
					(thickness 0.1778)
				)
			)
		)
		(property "Value" "0_5%_0402"
			(at 4.760695 2.013255 180)
			(unlocked yes)
			(layer "F.SilkS")
			(hide yes)
			(effects
				(font
					(face "Arial")
					(size 0.40005 0.40005)
					(thickness 0.1778)
				)
			)
		)
		(sheetname "01-M2_ZED-F9T_MODULE")
		(sheetfile "01-M2_ZED-F9T_MODULE.kicad_sch")
		(duplicate_pad_numbers_are_jumpers no)
		(fp_line
			(start 0.9 0.45)
			(end -0.9 0.45)
			(stroke
				(width 0.05)
				(type solid)
			)
			(layer "F.CrtYd")
		)
		(fp_line
			(start 0.9 -0.45)
			(end 0.9 0.45)
			(stroke
				(width 0.05)
				(type solid)
			)
			(layer "F.CrtYd")
		)
		(fp_line
			(start 0.9 -0.45)
			(end -0.9 -0.45)
			(stroke
				(width 0.05)
				(type solid)
			)
			(layer "F.CrtYd")
		)
		(fp_line
			(start 0.275 0)
			(end -0.275 0)
			(stroke
				(width 0.1)
				(type solid)
			)
			(layer "F.CrtYd")
		)
		(fp_line
			(start 0 -0.275)
			(end 0 0.275)
			(stroke
				(width 0.1)
				(type solid)
			)
			(layer "F.CrtYd")
		)
		(fp_line
			(start -0.9 -0.45)
			(end -0.9 0.45)
			(stroke
				(width 0.05)
				(type solid)
			)
			(layer "F.CrtYd")
		)
		(pad "1" smd rect
			(at -0.425 0 270)
			(size 0.55 0.6)
			(layers "F.Cu" "F.Mask" "F.Paste")
			(net "RX_GPS_CONN")
		)
		(pad "2" smd rect
			(at 0.425 0 270)
			(size 0.55 0.6)
			(layers "F.Cu" "F.Mask" "F.Paste")
			(net "NetR3_2")
		)
	)
	(footprint "Vault:FP-RMCF0402-MFG"
		(layer "F.Cu")
		(at 140.201105 112.9036 180)
		(property "Reference" "R7"
			(at 0 1.180485 0)
			(unlocked yes)
			(layer "F.SilkS")
			(effects
				(font
					(face "Arial")
					(size 0.40005 0.40005)
					(thickness 0.178)
				)
			)
		)
		(property "Value" "1k"
			(at 6.53812 1.956021 180)
			(unlocked yes)
			(layer "F.SilkS")
			(hide yes)
			(effects
				(font
					(face "Arial")
					(size 0.96012 0.96012)
					(thickness 0.254)
				)
			)
		)
		(sheetname "01-M2_ZED-F9T_MODULE")
		(sheetfile "01-M2_ZED-F9T_MODULE.kicad_sch")
		(duplicate_pad_numbers_are_jumpers no)
		(fp_line
			(start 0.55 0.7)
			(end -0.55 0.7)
			(stroke
				(width 0.2)
				(type solid)
			)
			(layer "F.SilkS")
		)
		(fp_line
			(start 0.55 -0.7)
			(end -0.55 -0.7)
			(stroke
				(width 0.2)
				(type solid)
			)
			(layer "F.SilkS")
		)
		(fp_line
			(start 0.85 0.4)
			(end -0.85 0.4)
			(stroke
				(width 0.2)
				(type solid)
			)
			(layer "F.CrtYd")
		)
		(fp_line
			(start 0.85 -0.4)
			(end 0.85 0.4)
			(stroke
				(width 0.2)
				(type solid)
			)
			(layer "F.CrtYd")
		)
		(fp_line
			(start 0.85 -0.4)
			(end -0.85 -0.4)
			(stroke
				(width 0.2)
				(type solid)
			)
			(layer "F.CrtYd")
		)
		(fp_line
			(start -0.85 -0.4)
			(end -0.85 0.4)
			(stroke
				(width 0.2)
				(type solid)
			)
			(layer "F.CrtYd")
		)
		(fp_line
			(start 0.85 0.4)
			(end -0.85 0.4)
			(stroke
				(width 0.2)
				(type solid)
			)
			(layer "F.Fab")
		)
		(fp_line
			(start 0.85 -0.4)
			(end 0.85 0.4)
			(stroke
				(width 0.2)
				(type solid)
			)
			(layer "F.Fab")
		)
		(fp_line
			(start 0.85 -0.4)
			(end -0.85 -0.4)
			(stroke
				(width 0.2)
				(type solid)
			)
			(layer "F.Fab")
		)
		(fp_line
			(start 0.5 0)
			(end -0.5 0)
			(stroke
				(width 0.1)
				(type solid)
			)
			(layer "F.Fab")
		)
		(fp_line
			(start 0 -0.5)
			(end 0 0.5)
			(stroke
				(width 0.1)
				(type solid)
			)
			(layer "F.Fab")
		)
		(fp_line
			(start -0.85 -0.4)
			(end -0.85 0.4)
			(stroke
				(width 0.2)
				(type solid)
			)
			(layer "F.Fab")
		)
		(fp_text user "${REFERENCE}"
			(at -0.00001 0.10711 180)
			(unlocked yes)
			(layer "F.Fab")
			(effects
				(font
					(face "Arial")
					(size 0.63 0.63)
					(thickness 0.1)
				)
				(justify left bottom)
			)
		)
		(pad "1" smd rect
			(at -0.5 0 180)
			(size 0.5 0.6)
			(layers "F.Cu" "F.Mask" "F.Paste")
			(net "GND")
			(solder_mask_margin 0)
			(solder_paste_margin 0)
		)
		(pad "2" smd rect
			(at 0.5 0 180)
			(size 0.5 0.6)
			(layers "F.Cu" "F.Mask" "F.Paste")
			(net "NetD3_1")
			(solder_mask_margin 0)
			(solder_paste_margin 0)
		)
	)
	(footprint "Vault:FP-RMCF0402-MFG"
		(layer "F.Cu")
		(at 145.701105 88.6786)
		(property "Reference" "R10"
			(at 0.549995 -1.158125 0)
			(unlocked yes)
			(layer "F.SilkS")
			(effects
				(font
					(face "Arial")
					(size 0.40005 0.40005)
					(thickness 0.1778)
				)
			)
		)
		(property "Value" "1k"
			(at 2.729345 2.066945 0)
			(unlocked yes)
			(layer "F.SilkS")
			(hide yes)
			(effects
				(font
					(face "Arial")
					(size 0.40005 0.40005)
					(thickness 0.1778)
				)
			)
		)
		(sheetname "02-Antenna_Supervisor")
		(sheetfile "02-Antenna_Supervisor.kicad_sch")
		(duplicate_pad_numbers_are_jumpers no)
		(fp_line
			(start -0.85 -0.4)
			(end 0.85 -0.4)
			(stroke
				(width 0.2)
				(type solid)
			)
			(layer "F.CrtYd")
		)
		(fp_line
			(start -0.85 0.4)
			(end -0.85 -0.4)
			(stroke
				(width 0.2)
				(type solid)
			)
			(layer "F.CrtYd")
		)
		(fp_line
			(start -0.85 0.4)
			(end 0.85 0.4)
			(stroke
				(width 0.2)
				(type solid)
			)
			(layer "F.CrtYd")
		)
		(fp_line
			(start 0.85 0.4)
			(end 0.85 -0.4)
			(stroke
				(width 0.2)
				(type solid)
			)
			(layer "F.CrtYd")
		)
		(fp_line
			(start -0.85 -0.4)
			(end 0.85 -0.4)
			(stroke
				(width 0.2)
				(type solid)
			)
			(layer "F.Fab")
		)
		(fp_line
			(start -0.85 0.4)
			(end -0.85 -0.4)
			(stroke
				(width 0.2)
				(type solid)
			)
			(layer "F.Fab")
		)
		(fp_line
			(start -0.85 0.4)
			(end 0.85 0.4)
			(stroke
				(width 0.2)
				(type solid)
			)
			(layer "F.Fab")
		)
		(fp_line
			(start -0.5 0)
			(end 0.5 0)
			(stroke
				(width 0.1)
				(type solid)
			)
			(layer "F.Fab")
		)
		(fp_line
			(start 0 0.5)
			(end 0 -0.5)
			(stroke
				(width 0.1)
				(type solid)
			)
			(layer "F.Fab")
		)
		(fp_line
			(start 0.85 0.4)
			(end 0.85 -0.4)
			(stroke
				(width 0.2)
				(type solid)
			)
			(layer "F.Fab")
		)
		(fp_text user "${REFERENCE}"
			(at -0.00001 0.09602 360)
			(unlocked yes)
			(layer "F.Fab")
			(effects
				(font
					(face "Arial")
					(size 0.63 0.63)
					(thickness 0.1)
				)
				(justify left bottom)
			)
		)
		(pad "1" smd rect
			(at -0.5 0)
			(size 0.5 0.6)
			(layers "F.Cu" "F.Mask" "F.Paste")
			(net "NetR10_1")
			(solder_mask_margin 0)
			(solder_paste_margin 0)
		)
		(pad "2" smd rect
			(at 0.5 0)
			(size 0.5 0.6)
			(layers "F.Cu" "F.Mask" "F.Paste")
			(net "NetQ1_3")
			(solder_mask_margin 0)
			(solder_paste_margin 0)
		)
	)
	(footprint "Vault:FP-RMCF0402-MFG"
		(layer "F.Cu")
		(at 140.101105 91.6036 -90)
		(property "Reference" "R17"
			(at -0.1 4.190519 90)
			(unlocked yes)
			(layer "F.SilkS")
			(effects
				(font
					(face "Arial")
					(size 0.96012 0.96012)
					(thickness 0.254)
				)
			)
		)
		(property "Value" "1k"
			(at -2.286231 0.46957 180)
			(unlocked yes)
			(layer "F.SilkS")
			(hide yes)
			(effects
				(font
					(face "Arial")
					(size 0.96012 0.96012)
					(thickness 0.254)
				)
			)
		)
		(sheetname "02-Antenna_Supervisor")
		(sheetfile "02-Antenna_Supervisor.kicad_sch")
		(duplicate_pad_numbers_are_jumpers no)
		(fp_line
			(start -0.85 0.4)
			(end -0.85 -0.4)
			(stroke
				(width 0.2)
				(type solid)
			)
			(layer "F.CrtYd")
		)
		(fp_line
			(start 0.85 0.4)
			(end -0.85 0.4)
			(stroke
				(width 0.2)
				(type solid)
			)
			(layer "F.CrtYd")
		)
		(fp_line
			(start 0.85 0.4)
			(end 0.85 -0.4)
			(stroke
				(width 0.2)
				(type solid)
			)
			(layer "F.CrtYd")
		)
		(fp_line
			(start 0.85 -0.4)
			(end -0.85 -0.4)
			(stroke
				(width 0.2)
				(type solid)
			)
			(layer "F.CrtYd")
		)
		(fp_line
			(start 0 0.5)
			(end 0 -0.5)
			(stroke
				(width 0.1)
				(type solid)
			)
			(layer "F.Fab")
		)
		(fp_line
			(start -0.85 0.4)
			(end -0.85 -0.4)
			(stroke
				(width 0.2)
				(type solid)
			)
			(layer "F.Fab")
		)
		(fp_line
			(start 0.85 0.4)
			(end -0.85 0.4)
			(stroke
				(width 0.2)
				(type solid)
			)
			(layer "F.Fab")
		)
		(fp_line
			(start 0.85 0.4)
			(end 0.85 -0.4)
			(stroke
				(width 0.2)
				(type solid)
			)
			(layer "F.Fab")
		)
		(fp_line
			(start 0.5 0)
			(end -0.5 0)
			(stroke
				(width 0.1)
				(type solid)
			)
			(layer "F.Fab")
		)
		(fp_line
			(start 0.85 -0.4)
			(end -0.85 -0.4)
			(stroke
				(width 0.2)
				(type solid)
			)
			(layer "F.Fab")
		)
		(fp_text user "${REFERENCE}"
			(at -0.00001 0.10711 270)
			(unlocked yes)
			(layer "F.Fab")
			(effects
				(font
					(face "Arial")
					(size 0.63 0.63)
					(thickness 0.1)
				)
				(justify left bottom)
			)
		)
		(pad "1" smd rect
			(at -0.5 0 270)
			(size 0.5 0.6)
			(layers "F.Cu" "F.Mask" "F.Paste")
			(net "ANT_DET")
			(solder_mask_margin 0)
			(solder_paste_margin 0)
		)
		(pad "2" smd rect
			(at 0.5 0 270)
			(size 0.5 0.6)
			(layers "F.Cu" "F.Mask" "F.Paste")
			(net "+3V3")
			(solder_mask_margin 0)
			(solder_paste_margin 0)
		)
	)
	(footprint "Vault:RESC1005X40X25NL05T10"
		(layer "F.Cu")
		(at 144.401105 117.9036 -90)
		(property "Reference" "R12"
			(at 0 1.495704 90)
			(unlocked yes)
			(layer "F.SilkS")
			(effects
				(font
					(face "Arial")
					(size 0.48006 0.48006)
					(thickness 0.254)
				)
			)
		)
		(property "Value" "0_5%_0402"
			(at -2.385831 6.512925 180)
			(unlocked yes)
			(layer "F.SilkS")
			(hide yes)
			(effects
				(font
					(face "Arial")
					(size 0.96012 0.96012)
					(thickness 0.254)
				)
			)
		)
		(sheetname "03-M2_GoldFingers")
		(sheetfile "03-M2_GoldFingers.kicad_sch")
		(duplicate_pad_numbers_are_jumpers no)
		(fp_line
			(start -0.9 0.45)
			(end -0.9 -0.45)
			(stroke
				(width 0.05)
				(type solid)
			)
			(layer "F.CrtYd")
		)
		(fp_line
			(start 0.9 0.45)
			(end -0.9 0.45)
			(stroke
				(width 0.05)
				(type solid)
			)
			(layer "F.CrtYd")
		)
		(fp_line
			(start 0.9 0.45)
			(end 0.9 -0.45)
			(stroke
				(width 0.05)
				(type solid)
			)
			(layer "F.CrtYd")
		)
		(fp_line
			(start 0 0.275)
			(end 0 -0.275)
			(stroke
				(width 0.1)
				(type solid)
			)
			(layer "F.CrtYd")
		)
		(fp_line
			(start 0.275 0)
			(end -0.275 0)
			(stroke
				(width 0.1)
				(type solid)
			)
			(layer "F.CrtYd")
		)
		(fp_line
			(start 0.9 -0.45)
			(end -0.9 -0.45)
			(stroke
				(width 0.05)
				(type solid)
			)
			(layer "F.CrtYd")
		)
		(pad "1" smd rect
			(at -0.425 0)
			(size 0.55 0.6)
			(layers "F.Cu" "F.Mask" "F.Paste")
			(net "RST_GPS")
		)
		(pad "2" smd rect
			(at 0.425 0)
			(size 0.55 0.6)
			(layers "F.Cu" "F.Mask" "F.Paste")
			(net "NetJ1_67")
		)
	)
	(footprint "Vault:DCK0005A_N"
		(layer "F.Cu")
		(at 142.601105 86.3306 90)
		(property "Reference" "U4"
			(at 0.3 2.301089 270)
			(unlocked yes)
			(layer "F.SilkS")
			(effects
				(font
					(face "Arial")
					(size 0.96012 0.96012)
					(thickness 0.254)
				)
			)
		)
		(property "Value" "LPV511MGX/NOPB"
			(at 8.59461 2.715911 90)
			(unlocked yes)
			(layer "F.SilkS")
			(hide yes)
			(effects
				(font
					(face "Arial")
					(size 0.96012 0.96012)
					(thickness 0.254)
				)
			)
		)
		(sheetname "02-Antenna_Supervisor")
		(sheetfile "02-Antenna_Supervisor.kicad_sch")
		(duplicate_pad_numbers_are_jumpers no)
		(fp_line
			(start 0.3 -1.1)
			(end 0.3 1.1)
			(stroke
				(width 0.2)
				(type solid)
			)
			(layer "F.SilkS")
		)
		(fp_line
			(start -0.3 -1.1)
			(end 0.3 -1.1)
			(stroke
				(width 0.2)
				(type solid)
			)
			(layer "F.SilkS")
		)
		(fp_line
			(start -0.3 -1.1)
			(end -0.3 1.1)
			(stroke
				(width 0.2)
				(type solid)
			)
			(layer "F.SilkS")
		)
		(fp_line
			(start -0.3 1.1)
			(end 0.3 1.1)
			(stroke
				(width 0.2)
				(type solid)
			)
			(layer "F.SilkS")
		)
		(fp_circle
			(center -1.125 -1.4)
			(end -1 -1.4)
			(stroke
				(width 0.25)
				(type solid)
			)
			(fill no)
			(layer "F.SilkS")
		)
		(fp_line
			(start 1.8 -1.35)
			(end 1.8 1.35)
			(stroke
				(width 0.05)
				(type solid)
			)
			(layer "F.CrtYd")
		)
		(fp_line
			(start -1.8 -1.35)
			(end 1.8 -1.35)
			(stroke
				(width 0.05)
				(type solid)
			)
			(layer "F.CrtYd")
		)
		(fp_line
			(start -1.8 -1.35)
			(end -1.8 1.35)
			(stroke
				(width 0.05)
				(type solid)
			)
			(layer "F.CrtYd")
		)
		(fp_line
			(start 0 -0.5)
			(end 0 0.5)
			(stroke
				(width 0.1)
				(type solid)
			)
			(layer "F.CrtYd")
		)
		(fp_line
			(start -0.5 0)
			(end 0.5 0)
			(stroke
				(width 0.1)
				(type solid)
			)
			(layer "F.CrtYd")
		)
		(fp_line
			(start -1.8 1.35)
			(end 1.8 1.35)
			(stroke
				(width 0.05)
				(type solid)
			)
			(layer "F.CrtYd")
		)
		(pad "1" smd roundrect
			(at -1.125 -0.65 180)
			(size 0.4 0.85)
			(layers "F.Cu" "F.Mask" "F.Paste")
			(roundrect_rratio 0.125)
			(net "NetU3_1")
		)
		(pad "2" smd roundrect
			(at -1.125 0 180)
			(size 0.4 0.85)
			(layers "F.Cu" "F.Mask" "F.Paste")
			(roundrect_rratio 0.125)
			(net "GND")
		)
		(pad "3" smd roundrect
			(at -1.125 0.65 180)
			(size 0.4 0.85)
			(layers "F.Cu" "F.Mask" "F.Paste")
			(roundrect_rratio 0.125)
			(net "NetR10_1")
		)
		(pad "4" smd roundrect
			(at 1.125 0.65 180)
			(size 0.4 0.85)
			(layers "F.Cu" "F.Mask" "F.Paste")
			(roundrect_rratio 0.125)
			(net "NetC12_1")
		)
		(pad "5" smd roundrect
			(at 1.125 -0.65 180)
			(size 0.4 0.85)
			(layers "F.Cu" "F.Mask" "F.Paste")
			(roundrect_rratio 0.125)
			(net "+3V3")
		)
	)
	(footprint "Vault:FP-RMCF0402-IPC_C"
		(layer "F.Cu")
		(at 143.801105 88.6798)
		(property "Reference" "R11"
			(at 1.15 -1.267744 0)
			(unlocked yes)
			(layer "F.SilkS")
			(effects
				(font
					(face "Arial")
					(size 0.48006 0.48006)
					(thickness 0.254)
				)
			)
		)
		(property "Value" "100k"
			(at -2.353971 7.960265 270)
			(unlocked yes)
			(layer "F.SilkS")
			(hide yes)
			(effects
				(font
					(face "Arial")
					(size 0.96012 0.96012)
					(thickness 0.254)
				)
			)
		)
		(sheetname "02-Antenna_Supervisor")
		(sheetfile "02-Antenna_Supervisor.kicad_sch")
		(duplicate_pad_numbers_are_jumpers no)
		(fp_line
			(start -0.75607 -0.375)
			(end 0.75607 -0.375)
			(stroke
				(width 0.2)
				(type solid)
			)
			(layer "F.CrtYd")
		)
		(fp_line
			(start -0.75607 0.375)
			(end -0.75607 -0.375)
			(stroke
				(width 0.2)
				(type solid)
			)
			(layer "F.CrtYd")
		)
		(fp_line
			(start -0.75607 0.375)
			(end 0.75607 0.375)
			(stroke
				(width 0.2)
				(type solid)
			)
			(layer "F.CrtYd")
		)
		(fp_line
			(start 0.75607 0.375)
			(end 0.75607 -0.375)
			(stroke
				(width 0.2)
				(type solid)
			)
			(layer "F.CrtYd")
		)
		(fp_line
			(start -0.75607 -0.375)
			(end 0.75607 -0.375)
			(stroke
				(width 0.2)
				(type solid)
			)
			(layer "F.Fab")
		)
		(fp_line
			(start -0.75607 0.375)
			(end -0.75607 -0.375)
			(stroke
				(width 0.2)
				(type solid)
			)
			(layer "F.Fab")
		)
		(fp_line
			(start -0.75607 0.375)
			(end 0.75607 0.375)
			(stroke
				(width 0.2)
				(type solid)
			)
			(layer "F.Fab")
		)
		(fp_line
			(start -0.5 0)
			(end 0.5 0)
			(stroke
				(width 0.1)
				(type solid)
			)
			(layer "F.Fab")
		)
		(fp_line
			(start 0 0.5)
			(end 0 -0.5)
			(stroke
				(width 0.1)
				(type solid)
			)
			(layer "F.Fab")
		)
		(fp_line
			(start 0.75607 0.375)
			(end 0.75607 -0.375)
			(stroke
				(width 0.2)
				(type solid)
			)
			(layer "F.Fab")
		)
		(fp_text user "${REFERENCE}"
			(at -0.00001 0.10711 360)
			(unlocked yes)
			(layer "F.Fab")
			(effects
				(font
					(face "Arial")
					(size 0.63 0.63)
					(thickness 0.1)
				)
				(justify left bottom)
			)
		)
		(pad "1" smd rect
			(at -0.36554 0)
			(size 0.58106 0.47247)
			(layers "F.Cu" "F.Mask" "F.Paste")
			(net "GND")
			(solder_mask_margin 0)
			(solder_paste_margin 0)
		)
		(pad "2" smd rect
			(at 0.36554 0)
			(size 0.58106 0.47247)
			(layers "F.Cu" "F.Mask" "F.Paste")
			(net "NetR10_1")
			(solder_mask_margin 0)
			(solder_paste_margin 0)
		)
	)
	(footprint "Vault:FP-CL542-IPC_C"
		(layer "F.Cu")
		(at 148.501105 110.5036)
		(property "Reference" "C2"
			(at 0 1.119515 0)
			(unlocked yes)
			(layer "F.SilkS")
			(effects
				(font
					(face "Arial")
					(size 0.40005 0.40005)
					(thickness 0.1778)
				)
			)
		)
		(property "Value" "1uF_25V_0402"
			(at 5.52245 1.959815 0)
			(unlocked yes)
			(layer "F.SilkS")
			(hide yes)
			(effects
				(font
					(face "Arial")
					(size 0.40005 0.40005)
					(thickness 0.1778)
				)
			)
		)
		(sheetname "01-M2_ZED-F9T_MODULE")
		(sheetfile "01-M2_ZED-F9T_MODULE.kicad_sch")
		(duplicate_pad_numbers_are_jumpers no)
		(fp_line
			(start -0.63624 -0.675)
			(end 0.63624 -0.675)
			(stroke
				(width 0.2)
				(type solid)
			)
			(layer "F.SilkS")
		)
		(fp_line
			(start -0.63624 0.675)
			(end 0.63624 0.675)
			(stroke
				(width 0.2)
				(type solid)
			)
			(layer "F.SilkS")
		)
		(fp_line
			(start -0.73624 -0.375)
			(end 0.73624 -0.375)
			(stroke
				(width 0.2)
				(type solid)
			)
			(layer "F.CrtYd")
		)
		(fp_line
			(start -0.73624 0.375)
			(end -0.73624 -0.375)
			(stroke
				(width 0.2)
				(type solid)
			)
			(layer "F.CrtYd")
		)
		(fp_line
			(start -0.73624 0.375)
			(end 0.73624 0.375)
			(stroke
				(width 0.2)
				(type solid)
			)
			(layer "F.CrtYd")
		)
		(fp_line
			(start 0.73624 0.375)
			(end 0.73624 -0.375)
			(stroke
				(width 0.2)
				(type solid)
			)
			(layer "F.CrtYd")
		)
		(fp_line
			(start -0.73624 -0.375)
			(end 0.73624 -0.375)
			(stroke
				(width 0.2)
				(type solid)
			)
			(layer "F.Fab")
		)
		(fp_line
			(start -0.73624 0.375)
			(end -0.73624 -0.375)
			(stroke
				(width 0.2)
				(type solid)
			)
			(layer "F.Fab")
		)
		(fp_line
			(start -0.73624 0.375)
			(end 0.73624 0.375)
			(stroke
				(width 0.2)
				(type solid)
			)
			(layer "F.Fab")
		)
		(fp_line
			(start -0.5 0)
			(end 0.5 0)
			(stroke
				(width 0.1)
				(type solid)
			)
			(layer "F.Fab")
		)
		(fp_line
			(start -0.5 0)
			(end 0.5 0)
			(stroke
				(width 0.1)
				(type solid)
			)
			(layer "F.Fab")
		)
		(fp_line
			(start 0 0.5)
			(end 0 -0.5)
			(stroke
				(width 0.1)
				(type solid)
			)
			(layer "F.Fab")
		)
		(fp_line
			(start 0 0.5)
			(end 0 -0.5)
			(stroke
				(width 0.1)
				(type solid)
			)
			(layer "F.Fab")
		)
		(fp_line
			(start 0.73624 0.375)
			(end 0.73624 -0.375)
			(stroke
				(width 0.2)
				(type solid)
			)
			(layer "F.Fab")
		)
		(fp_text user "${REFERENCE}"
			(at 0 0.28425 360)
			(unlocked yes)
			(layer "F.Fab")
			(effects
				(font
					(face "Arial")
					(size 0.63 0.63)
					(thickness 0.1)
				)
				(justify left bottom)
			)
		)
		(pad "1" smd rect
			(at -0.37856 0)
			(size 0.51535 0.47247)
			(layers "F.Cu" "F.Mask" "F.Paste")
			(net "+3V3")
			(solder_mask_margin 0)
			(solder_paste_margin 0)
		)
		(pad "2" smd rect
			(at 0.37856 0)
			(size 0.51535 0.47247)
			(layers "F.Cu" "F.Mask" "F.Paste")
			(net "GND")
			(solder_mask_margin 0)
			(solder_paste_margin 0)
		)
	)
	(gr_line
		(start 137.501095 84.0036)
		(end 159.501095 84.0036)
		(stroke
			(width 0.05)
			(type solid)
		)
		(layer "Edge.Cuts")
	)
	(gr_line
		(start 137.501105 122.85359)
		(end 137.501095 84.0036)
		(stroke
			(width 0.05)
			(type solid)
		)
		(layer "Edge.Cuts")
	)
	(gr_line
		(start 138.0761 122.85359)
		(end 138.076105 122.85359)
		(stroke
			(width 0.05)
			(type solid)
		)
		(layer "Edge.Cuts")
	)
	(gr_arc
		(start 138.0761 122.85359)
		(mid 138.429662 123.000036)
		(end 138.576095 123.353595)
		(stroke
			(width 0.05)
			(type solid)
		)
		(layer "Edge.Cuts")
	)
	(gr_line
		(start 138.076105 122.85359)
		(end 137.501105 122.85359)
		(stroke
			(width 0.05)
			(type solid)
		)
		(layer "Edge.Cuts")
	)
	(gr_line
		(start 138.576105 126.0036)
		(end 138.576095 123.353595)
		(stroke
			(width 0.05)
			(type solid)
		)
		(layer "Edge.Cuts")
	)
	(gr_line
		(start 153.526105 123.1036)
		(end 153.526105 126.0036)
		(stroke
			(width 0.05)
			(type solid)
		)
		(layer "Edge.Cuts")
	)
	(gr_arc
		(start 153.526105 123.1036)
		(mid 154.126105 122.5036)
		(end 154.726105 123.1036)
		(stroke
			(width 0.05)
			(type solid)
		)
		(layer "Edge.Cuts")
	)
	(gr_line
		(start 153.526105 126.0036)
		(end 138.576105 126.0036)
		(stroke
			(width 0.05)
			(type solid)
		)
		(layer "Edge.Cuts")
	)
	(gr_line
		(start 154.726105 126.0036)
		(end 154.726105 123.1036)
		(stroke
			(width 0.05)
			(type solid)
		)
		(layer "Edge.Cuts")
	)
	(gr_line
		(start 158.426105 123.3536)
		(end 158.426105 126.0036)
		(stroke
			(width 0.05)
			(type solid)
		)
		(layer "Edge.Cuts")
	)
	(gr_arc
		(start 158.426105 123.3536)
		(mid 158.572555 123.000043)
		(end 158.926115 122.85359)
		(stroke
			(width 0.05)
			(type solid)
		)
		(layer "Edge.Cuts")
	)
	(gr_line
		(start 158.426105 126.0036)
		(end 154.726105 126.0036)
		(stroke
			(width 0.05)
			(type solid)
		)
		(layer "Edge.Cuts")
	)
	(gr_line
		(start 159.501095 84.0036)
		(end 159.501105 122.85359)
		(stroke
			(width 0.05)
			(type solid)
		)
		(layer "Edge.Cuts")
	)
	(gr_line
		(start 159.501105 122.85359)
		(end 158.926115 122.85359)
		(stroke
			(width 0.05)
			(type solid)
		)
		(layer "Edge.Cuts")
	)
	(segment
		(start 154.101105 114.8036)
		(end 156.001105 114.8036)
		(width 0.1905)
		(layer "F.Cu")
		(net "NetR3_2")
	)
	(segment
		(start 144.913005 115.96669)
		(end 144.976105 115.9036)
		(width 0.1905)
		(layer "F.Cu")
		(net "NetR3_2")
	)
	(segment
		(start 157.501105 114.5036)
		(end 157.901105 114.9036)
		(width 0.1905)
		(layer "F.Cu")
		(net "NetR3_2")
	)
	(segment
		(start 156.301105 114.5036)
		(end 157.501105 114.5036)
		(width 0.1905)
		(layer "F.Cu")
		(net "NetR3_2")
	)
	(segment
		(start 144.099945 115.96669)
		(end 144.913005 115.96669)
		(width 0.1905)
		(layer "F.Cu")
		(net "NetR3_2")
	)
	(segment
		(start 156.001105 114.8036)
		(end 156.301105 114.5036)
		(width 0.1905)
		(layer "F.Cu")
		(net "NetR3_2")
	)
	(via
		(at 158.501105 106.79359)
		(size 0.4064)
		(drill 0.254)
		(layers "F.Cu" "B.Cu")
		(net "NetR3_2")
	)
	(via
		(at 154.101105 114.8036)
		(size 0.4064)
		(drill 0.254)
		(layers "F.Cu" "B.Cu")
		(net "NetR3_2")
	)
	(via
		(at 157.901105 114.9036)
		(size 0.4064)
		(drill 0.254)
		(layers "F.Cu" "B.Cu")
		(net "NetR3_2")
	)
	(via
		(at 144.099945 115.96669)
		(size 0.4064)
		(drill 0.254)
		(layers "F.Cu" "B.Cu")
		(net "NetR3_2")
	)
	(segment
		(start 144.888015 115.96669)
		(end 146.501105 114.3536)
		(width 0.1905)
		(layer "B.Cu")
		(net "NetR3_2")
	)
	(segment
		(start 146.501105 114.3536)
		(end 153.651105 114.3536)
		(width 0.1905)
		(layer "B.Cu")
		(net "NetR3_2")
	)
	(segment
		(start 157.001105 114.7036)
		(end 157.001105 112.7036)
		(width 0.1905)
		(layer "B.Cu")
		(net "NetR3_2")
	)
	(segment
		(start 157.001105 112.7036)
		(end 158.001105 111.7036)
		(width 0.1905)
		(layer "B.Cu")
		(net "NetR3_2")
	)
	(segment
		(start 144.099945 115.96669)
		(end 144.888015 115.96669)
		(width 0.1905)
		(layer "B.Cu")
		(net "NetR3_2")
	)
	(segment
		(start 157.001105 114.7036)
		(end 157.201105 114.9036)
		(width 0.1905)
		(layer "B.Cu")
		(net "NetR3_2")
	)
	(segment
		(start 157.201105 114.9036)
		(end 157.901105 114.9036)
		(width 0.1905)
		(layer "B.Cu")
		(net "NetR3_2")
	)
	(segment
		(start 153.651105 114.3536)
		(end 154.101105 114.8036)
		(width 0.1905)
		(layer "B.Cu")
		(net "NetR3_2")
	)
	(segment
		(start 158.001105 111.7036)
		(end 158.001105 107.29359)
		(width 0.1905)
		(layer "B.Cu")
		(net "NetR3_2")
	)
	(segment
		(start 158.001105 107.29359)
		(end 158.501105 106.79359)
		(width 0.1905)
		(layer "B.Cu")
		(net "NetR3_2")
	)
	(segment
		(start 154.201105 114.0036)
		(end 157.601105 114.0036)
		(width 0.1905)
		(layer "F.Cu")
		(net "NetR2_2")
	)
	(segment
		(start 144.101105 114.8036)
		(end 144.976105 114.8036)
		(width 0.1905)
		(layer "F.Cu")
		(net "NetR2_2")
	)
	(via
		(at 157.601105 114.0036)
		(size 0.4064)
		(drill 0.254)
		(layers "F.Cu" "B.Cu")
		(net "NetR2_2")
	)
	(via
		(at 158.501105 107.89359)
		(size 0.4064)
		(drill 0.254)
		(layers "F.Cu" "B.Cu")
		(net "NetR2_2")
	)
	(via
		(at 144.101105 114.8036)
		(size 0.4064)
		(drill 0.254)
		(layers "F.Cu" "B.Cu")
		(net "NetR2_2")
	)
	(via
		(at 154.201105 114.0036)
		(size 0.4064)
		(drill 0.254)
		(layers "F.Cu" "B.Cu")
		(net "NetR2_2")
	)
	(segment
		(start 157.601105 114.0036)
		(end 157.601105 112.8036)
		(width 0.1905)
		(layer "B.Cu")
		(net "NetR2_2")
	)
	(segment
		(start 144.101105 114.8036)
		(end 145.601105 114.8036)
		(width 0.1905)
		(layer "B.Cu")
		(net "NetR2_2")
	)
	(segment
		(start 146.401105 114.0036)
		(end 154.201105 114.0036)
		(width 0.1905)
		(layer "B.Cu")
		(net "NetR2_2")
	)
	(segment
		(start 145.601105 114.8036)
		(end 146.401105 114.0036)
		(width 0.1905)
		(layer "B.Cu")
		(net "NetR2_2")
	)
	(segment
		(start 158.501105 111.9036)
		(end 158.501105 107.89359)
		(width 0.1905)
		(layer "B.Cu")
		(net "NetR2_2")
	)
	(segment
		(start 157.601105 112.8036)
		(end 158.501105 111.9036)
		(width 0.1905)
		(layer "B.Cu")
		(net "NetR2_2")
	)
	(segment
		(start 139.451105 114.10863)
		(end 139.451105 113.2036)
		(width 0.3048)
		(layer "F.Cu")
		(net "NetD3_1")
	)
	(segment
		(start 139.701105 112.9536)
		(end 139.701105 112.9036)
		(width 0.3048)
		(layer "F.Cu")
		(net "NetD3_1")
	)
	(segment
		(start 139.451105 113.2036)
		(end 139.701105 112.9536)
		(width 0.3048)
		(layer "F.Cu")
		(net "NetD3_1")
	)
	(segment
		(start 139.288945 114.27079)
		(end 139.451105 114.10863)
		(width 0.3048)
		(layer "F.Cu")
		(net "NetD3_1")
	)
	(segment
		(start 154.001105 116.3036)
		(end 155.151105 116.3036)
		(width 0.1905)
		(layer "F.Cu")
		(net "NetD2_1")
	)
	(segment
		(start 144.401105 113.3036)
		(end 145.162195 113.3036)
		(width 0.1905)
		(layer "F.Cu")
		(net "NetC5_2")
	)
	(segment
		(start 144.401105 113.3036)
		(end 144.401105 112.0036)
		(width 0.1905)
		(layer "F.Cu")
		(net "NetC5_2")
	)
	(segment
		(start 145.162195 113.3036)
		(end 145.162195 113.28638)
		(width 0.1905)
		(layer "F.Cu")
		(net "NetC5_2")
	)
	(segment
		(start 144.279665 113.3036)
		(end 144.401105 113.3036)
		(width 0.1905)
		(layer "F.Cu")
		(net "NetC5_2")
	)
	(via
		(at 145.162195 113.28638)
		(size 0.4064)
		(drill 0.254)
		(layers "F.Cu" "B.Cu")
		(net "NetC5_2")
	)
	(via
		(at 158.501105 102.39359)
		(size 0.4064)
		(drill 0.254)
		(layers "F.Cu" "B.Cu")
		(net "NetC5_2")
	)
	(segment
		(start 145.162195 113.28638)
		(end 152.783885 113.28638)
		(width 0.1905)
		(layer "B.Cu")
		(net "NetC5_2")
	)
	(segment
		(start 154.601105 110.2211)
		(end 154.601105 102.4036)
		(width 0.1905)
		(layer "B.Cu")
		(net "NetC5_2")
	)
	(segment
		(start 158.501105 102.39359)
		(end 158.976395 101.9183)
		(width 0.1905)
		(layer "B.Cu")
		(net "NetC5_2")
	)
	(segment
		(start 154.601105 102.4036)
		(end 157.601105 99.4036)
		(width 0.1905)
		(layer "B.Cu")
		(net "NetC5_2")
	)
	(segment
		(start 158.976395 101.9183)
		(end 158.976395 99.86835)
		(width 0.1905)
		(layer "B.Cu")
		(net "NetC5_2")
	)
	(segment
		(start 153.001105 113.5036)
		(end 154.501105 113.5036)
		(width 0.1905)
		(layer "B.Cu")
		(net "NetC5_2")
	)
	(segment
		(start 154.601105 110.2211)
		(end 154.883605 110.5036)
		(width 0.1905)
		(layer "B.Cu")
		(net "NetC5_2")
	)
	(segment
		(start 154.501105 113.5036)
		(end 154.883605 113.1211)
		(width 0.1905)
		(layer "B.Cu")
		(net "NetC5_2")
	)
	(segment
		(start 157.601105 99.4036)
		(end 158.511645 99.4036)
		(width 0.1905)
		(layer "B.Cu")
		(net "NetC5_2")
	)
	(segment
		(start 158.511645 99.4036)
		(end 158.976395 99.86835)
		(width 0.1905)
		(layer "B.Cu")
		(net "NetC5_2")
	)
	(segment
		(start 154.883605 113.1211)
		(end 154.883605 110.5036)
		(width 0.1905)
		(layer "B.Cu")
		(net "NetC5_2")
	)
	(segment
		(start 152.783885 113.28638)
		(end 153.001105 113.5036)
		(width 0.1905)
		(layer "B.Cu")
		(net "NetC5_2")
	)
	(segment
		(start 145.826105 114.8036)
		(end 146.958575 114.8036)
		(width 0.1905)
		(layer "F.Cu")
		(net "TX_GPS_CONN")
	)
	(segment
		(start 146.958575 114.8036)
		(end 146.980445 114.78173)
		(width 0.1905)
		(layer "F.Cu")
		(net "TX_GPS_CONN")
	)
	(via
		(at 146.980445 114.78173)
		(size 0.4064)
		(drill 0.254)
		(layers "F.Cu" "B.Cu")
		(net "TX_GPS_CONN")
	)
	(segment
		(start 146.980445 114.82426)
		(end 146.980445 114.78173)
		(width 0.1905)
		(layer "B.Cu")
		(net "TX_GPS_CONN")
	)
	(segment
		(start 142.007105 124.4786)
		(end 142.007105 119.7976)
		(width 0.1905)
		(layer "B.Cu")
		(net "TX_GPS_CONN")
	)
	(segment
		(start 142.007105 119.7976)
		(end 146.980445 114.82426)
		(width 0.1905)
		(layer "B.Cu")
		(net "TX_GPS_CONN")
	)
	(segment
		(start 156.651105 116.3036)
		(end 156.651105 115.6536)
		(width 0.1905)
		(layer "F.Cu")
		(net "TP2")
	)
	(segment
		(start 153.201105 114.0036)
		(end 154.301105 112.9036)
		(width 0.1905)
		(layer "F.Cu")
		(net "TP2")
	)
	(segment
		(start 153.201105 114.7036)
		(end 153.201105 114.0036)
		(width 0.1905)
		(layer "F.Cu")
		(net "TP2")
	)
	(segment
		(start 153.801105 115.3036)
		(end 156.301105 115.3036)
		(width 0.1905)
		(layer "F.Cu")
		(net "TP2")
	)
	(segment
		(start 156.301105 115.3036)
		(end 156.651105 115.6536)
		(width 0.1905)
		(layer "F.Cu")
		(net "TP2")
	)
	(segment
		(start 153.201105 114.7036)
		(end 153.801105 115.3036)
		(width 0.1905)
		(layer "F.Cu")
		(net "TP2")
	)
	(via
		(at 154.301105 112.9036)
		(size 0.4064)
		(drill 0.254)
		(layers "F.Cu" "B.Cu")
		(net "TP2")
	)
	(via
		(at 158.501105 94.69359)
		(size 0.4064)
		(drill 0.254)
		(layers "F.Cu" "B.Cu")
		(net "TP2")
	)
	(segment
		(start 147.201105 110.71365)
		(end 147.201105 108.42787)
		(width 0.1905)
		(layer "B.Cu")
		(net "TP2")
	)
	(segment
		(start 149.108215 112.9036)
		(end 154.301105 112.9036)
		(width 0.1905)
		(layer "B.Cu")
		(net "TP2")
	)
	(segment
		(start 146.701105 107.22076)
		(end 146.701105 95.72786)
		(width 0.1905)
		(layer "B.Cu")
		(net "TP2")
	)
	(segment
		(start 147.749525 94.69359)
		(end 158.501105 94.69359)
		(width 0.1905)
		(layer "B.Cu")
		(net "TP2")
	)
	(arc
		(start 147.001102 95.003597)
		(mid 147.344481 94.774158)
		(end 147.749525 94.69359)
		(width 0.1778)
		(layer "B.Cu")
		(net "TP2")
	)
	(arc
		(start 147.901102 112.403593)
		(mid 147.383028 111.628241)
		(end 147.201105 110.71365)
		(width 0.1778)
		(layer "B.Cu")
		(net "TP2")
	)
	(arc
		(start 149.108215 112.9036)
		(mid 148.454932 112.773654)
		(end 147.901106 112.403599)
		(width 0.1778)
		(layer "B.Cu")
		(net "TP2")
	)
	(arc
		(start 146.701105 95.72786)
		(mid 146.779072 95.335893)
		(end 147.001104 95.003599)
		(width 0.1778)
		(layer "B.Cu")
		(net "TP2")
	)
	(arc
		(start 146.901103 107.703602)
		(mid 147.123137 108.035899)
		(end 147.201105 108.42787)
		(width 0.1778)
		(layer "B.Cu")
		(net "TP2")
	)
	(arc
		(start 146.901104 107.703601)
		(mid 146.753083 107.482072)
		(end 146.701105 107.22076)
		(width 0.1778)
		(layer "B.Cu")
		(net "TP2")
	)
	(segment
		(start 145.826105 115.9036)
		(end 145.885645 115.84406)
		(width 0.1905)
		(layer "F.Cu")
		(net "RX_GPS_CONN")
	)
	(segment
		(start 145.885645 115.84406)
		(end 146.806805 115.84406)
		(width 0.1905)
		(layer "F.Cu")
		(net "RX_GPS_CONN")
	)
	(via
		(at 146.806805 115.84406)
		(size 0.4064)
		(drill 0.254)
		(layers "F.Cu" "B.Cu")
		(net "RX_GPS_CONN")
	)
	(segment
		(start 146.482085 116.52262)
		(end 146.482085 116.18388)
		(width 0.1905)
		(layer "B.Cu")
		(net "RX_GPS_CONN")
	)
	(segment
		(start 146.201105 116.8036)
		(end 146.482085 116.52262)
		(width 0.1905)
		(layer "B.Cu")
		(net "RX_GPS_CONN")
	)
	(segment
		(start 146.482085 116.18388)
		(end 146.806805 115.85916)
		(width 0.1905)
		(layer "B.Cu")
		(net "RX_GPS_CONN")
	)
	(segment
		(start 145.994335 116.8036)
		(end 146.201105 116.8036)
		(width 0.1905)
		(layer "B.Cu")
		(net "RX_GPS_CONN")
	)
	(segment
		(start 142.507105 120.29083)
		(end 145.994335 116.8036)
		(width 0.1905)
		(layer "B.Cu")
		(net "RX_GPS_CONN")
	)
	(segment
		(start 146.806805 115.85916)
		(end 146.806805 115.84406)
		(width 0.1905)
		(layer "B.Cu")
		(net "RX_GPS_CONN")
	)
	(segment
		(start 142.507105 124.4786)
		(end 142.507105 120.29083)
		(width 0.1905)
		(layer "B.Cu")
		(net "RX_GPS_CONN")
	)
	(segment
		(start 154.601105 91.53216)
		(end 154.601105 91.53217)
		(width 0.1905)
		(layer "F.Cu")
		(net "RF_IN")
	)
	(segment
		(start 154.601105 93.84359)
		(end 154.601105 91.53217)
		(width 0.1905)
		(layer "F.Cu")
		(net "RF_IN")
	)
	(segment
		(start 141.105265 87.3036)
		(end 141.926105 87.3036)
		(width 0.1905)
		(layer "F.Cu")
		(net "NetU3_1")
	)
	(segment
		(start 141.001105 87.19945)
		(end 141.105265 87.3036)
		(width 0.1905)
		(layer "F.Cu")
		(net "NetU3_1")
	)
	(segment
		(start 140.896945 86.8036)
		(end 141.001105 86.90776)
		(width 0.1905)
		(layer "F.Cu")
		(net "NetU3_1")
	)
	(segment
		(start 141.001105 87.19945)
		(end 141.001105 86.90776)
		(width 0.1905)
		(layer "F.Cu")
		(net "NetU3_1")
	)
	(segment
		(start 140.351105 86.8036)
		(end 140.896945 86.8036)
		(width 0.1905)
		(layer "F.Cu")
		(net "NetU3_1")
	)
	(segment
		(start 141.926105 87.3036)
		(end 141.951105 87.3286)
		(width 0.1905)
		(layer "F.Cu")
		(net "NetU3_1")
	)
	(segment
		(start 144.166645 88.6036)
		(end 144.301105 88.46914)
		(width 0.1905)
		(layer "F.Cu")
		(net "NetR10_1")
	)
	(segment
		(start 144.301105 88.46914)
		(end 144.301105 87.50776)
		(width 0.1905)
		(layer "F.Cu")
		(net "NetR10_1")
	)
	(segment
		(start 143.326105 87.4036)
		(end 144.196945 87.4036)
		(width 0.1905)
		(layer "F.Cu")
		(net "NetR10_1")
	)
	(segment
		(start 144.295935 88.6786)
		(end 145.201105 88.6786)
		(width 0.381)
		(layer "F.Cu")
		(net "NetR10_1")
	)
	(segment
		(start 143.251105 87.3286)
		(end 143.326105 87.4036)
		(width 0.1905)
		(layer "F.Cu")
		(net "NetR10_1")
	)
	(segment
		(start 144.196945 87.4036)
		(end 144.301105 87.50776)
		(width 0.1905)
		(layer "F.Cu")
		(net "NetR10_1")
	)
	(segment
		(start 144.372445 85.67494)
		(end 146.101105 87.4036)
		(width 0.1905)
		(layer "F.Cu")
		(net "NetC12_1")
	)
	(segment
		(start 139.351105 86.8036)
		(end 139.351105 86.02173)
		(width 0.1905)
		(layer "F.Cu")
		(net "NetC12_1")
	)
	(segment
		(start 149.501105 88.4036)
		(end 149.701105 88.6036)
		(width 0.508)
		(layer "F.Cu")
		(net "NetC12_1")
	)
	(segment
		(start 143.251105 85.2536)
		(end 143.251105 85.0786)
		(width 0.1905)
		(layer "F.Cu")
		(net "NetC12_1")
	)
	(segment
		(start 143.251105 85.2536)
		(end 143.362205 85.3647)
		(width 0.1905)
		(layer "F.Cu")
		(net "NetC12_1")
	)
	(segment
		(start 143.362205 85.3647)
		(end 144.062205 85.3647)
		(width 0.1905)
		(layer "F.Cu")
		(net "NetC12_1")
	)
	(segment
		(start 149.701105 88.6036)
		(end 152.601105 88.6036)
		(width 0.508)
		(layer "F.Cu")
		(net "NetC12_1")
	)
	(segment
		(start 139.244135 85.91476)
		(end 139.351105 86.02173)
		(width 0.1905)
		(layer "F.Cu")
		(net "NetC12_1")
	)
	(segment
		(start 144.062205 85.3647)
		(end 144.372445 85.67494)
		(width 0.1905)
		(layer "F.Cu")
		(net "NetC12_1")
	)
	(segment
		(start 146.601105 87.4036)
		(end 147.601105 88.4036)
		(width 0.1905)
		(layer "F.Cu")
		(net "NetC12_1")
	)
	(segment
		(start 152.697275 89.57079)
		(end 152.697275 88.69977)
		(width 0.381)
		(layer "F.Cu")
		(net "NetC12_1")
	)
	(segment
		(start 139.244135 85.91476)
		(end 139.244135 85.8529)
		(width 0.1905)
		(layer "F.Cu")
		(net "NetC12_1")
	)
	(segment
		(start 146.101105 87.4036)
		(end 146.601105 87.4036)
		(width 0.1905)
		(layer "F.Cu")
		(net "NetC12_1")
	)
	(segment
		(start 152.601105 88.6036)
		(end 152.697275 88.69977)
		(width 0.381)
		(layer "F.Cu")
		(net "NetC12_1")
	)
	(segment
		(start 147.601105 88.4036)
		(end 149.501105 88.4036)
		(width 0.1905)
		(layer "F.Cu")
		(net "NetC12_1")
	)
	(segment
		(start 152.706405 89.56166)
		(end 153.724365 89.56166)
		(width 0.381)
		(layer "F.Cu")
		(net "NetC12_1")
	)
	(segment
		(start 152.697275 89.59766)
		(end 152.697275 89.57079)
		(width 0.381)
		(layer "F.Cu")
		(net "NetC12_1")
	)
	(segment
		(start 153.724365 89.56166)
		(end 153.760365 89.52566)
		(width 0.381)
		(layer "F.Cu")
		(net "NetC12_1")
	)
	(segment
		(start 152.697275 89.57079)
		(end 152.706405 89.56166)
		(width 0.381)
		(layer "F.Cu")
		(net "NetC12_1")
	)
	(via
		(at 144.372445 85.67494)
		(size 0.4064)
		(drill 0.254)
		(layers "F.Cu" "B.Cu")
		(net "NetC12_1")
	)
	(via
		(at 139.244135 85.8529)
		(size 0.4064)
		(drill 0.254)
		(layers "F.Cu" "B.Cu")
		(net "NetC12_1")
	)
	(segment
		(start 139.244135 85.8529)
		(end 140.080615 85.01642)
		(width 0.1905)
		(layer "B.Cu")
		(net "NetC12_1")
	)
	(segment
		(start 141.201105 85.01642)
		(end 141.859625 85.67494)
		(width 0.1905)
		(layer "B.Cu")
		(net "NetC12_1")
	)
	(segment
		(start 140.080615 85.01642)
		(end 141.201105 85.01642)
		(width 0.1905)
		(layer "B.Cu")
		(net "NetC12_1")
	)
	(segment
		(start 141.859625 85.67494)
		(end 144.372445 85.67494)
		(width 0.1905)
		(layer "B.Cu")
		(net "NetC12_1")
	)
	(segment
		(start 138.601105 91.1036)
		(end 138.651105 91.1036)
		(width 0.1905)
		(layer "F.Cu")
		(net "ANT_SHORT_N")
	)
	(segment
		(start 150.192015 92.60044)
		(end 150.201105 92.60953)
		(width 0.1905)
		(layer "F.Cu")
		(net "ANT_SHORT_N")
	)
	(segment
		(start 138.851105 90.9036)
		(end 138.851105 90.0036)
		(width 0.1905)
		(layer "F.Cu")
		(net "ANT_SHORT_N")
	)
	(segment
		(start 150.201105 93.84359)
		(end 150.201105 92.60953)
		(width 0.1905)
		(layer "F.Cu")
		(net "ANT_SHORT_N")
	)
	(segment
		(start 138.651105 91.1036)
		(end 138.851105 90.9036)
		(width 0.1905)
		(layer "F.Cu")
		(net "ANT_SHORT_N")
	)
	(via
		(at 150.192015 92.60044)
		(size 0.4064)
		(drill 0.254)
		(layers "F.Cu" "B.Cu")
		(net "ANT_SHORT_N")
	)
	(via
		(at 138.601105 91.1036)
		(size 0.4064)
		(drill 0.254)
		(layers "F.Cu" "B.Cu")
		(net "ANT_SHORT_N")
	)
	(segment
		(start 138.642415 91.29757)
		(end 138.644845 91.3)
		(width 0.1905)
		(layer "B.Cu")
		(net "ANT_SHORT_N")
	)
	(segment
		(start 138.644845 91.53983)
		(end 139.705455 92.60044)
		(width 0.1905)
		(layer "B.Cu")
		(net "ANT_SHORT_N")
	)
	(segment
		(start 138.642415 91.29757)
		(end 138.642415 91.14491)
		(width 0.1905)
		(layer "B.Cu")
		(net "ANT_SHORT_N")
	)
	(segment
		(start 138.601105 91.1036)
		(end 138.642415 91.14491)
		(width 0.1905)
		(layer "B.Cu")
		(net "ANT_SHORT_N")
	)
	(segment
		(start 139.705455 92.60044)
		(end 150.192015 92.60044)
		(width 0.1905)
		(layer "B.Cu")
		(net "ANT_SHORT_N")
	)
	(segment
		(start 138.644845 91.53983)
		(end 138.644845 91.3)
		(width 0.1905)
		(layer "B.Cu")
		(net "ANT_SHORT_N")
	)
	(segment
		(start 139.352055 91.60321)
		(end 139.352995 91.60415)
		(width 0.1905)
		(layer "F.Cu")
		(net "ANT_OFF")
	)
	(segment
		(start 139.352055 91.60321)
		(end 139.352055 90.00455)
		(width 0.1905)
		(layer "F.Cu")
		(net "ANT_OFF")
	)
	(segment
		(start 151.301105 93.84359)
		(end 151.301105 92.68996)
		(width 0.1905)
		(layer "F.Cu")
		(net "ANT_OFF")
	)
	(segment
		(start 139.351105 90.0036)
		(end 139.352055 90.00455)
		(width 0.1905)
		(layer "F.Cu")
		(net "ANT_OFF")
	)
	(segment
		(start 151.283375 92.67223)
		(end 151.301105 92.68996)
		(width 0.1905)
		(layer "F.Cu")
		(net "ANT_OFF")
	)
	(via
		(at 139.352995 91.60415)
		(size 0.4064)
		(drill 0.254)
		(layers "F.Cu" "B.Cu")
		(net "ANT_OFF")
	)
	(via
		(at 151.283375 92.67223)
		(size 0.4064)
		(drill 0.254)
		(layers "F.Cu" "B.Cu")
		(net "ANT_OFF")
	)
	(segment
		(start 141.601105 91.68141)
		(end 141.601105 91.2036)
		(width 0.1905)
		(layer "B.Cu")
		(net "ANT_OFF")
	)
	(segment
		(start 139.352995 91.68141)
		(end 139.352995 91.60415)
		(width 0.1905)
		(layer "B.Cu")
		(net "ANT_OFF")
	)
	(segment
		(start 143.010345 91.8536)
		(end 143.010345 91.2036)
		(width 0.1905)
		(layer "B.Cu")
		(net "ANT_OFF")
	)
	(segment
		(start 143.010345 91.8536)
		(end 150.464745 91.8536)
		(width 0.1905)
		(layer "B.Cu")
		(net "ANT_OFF")
	)
	(segment
		(start 150.464745 91.8536)
		(end 151.283375 92.67223)
		(width 0.1905)
		(layer "B.Cu")
		(net "ANT_OFF")
	)
	(segment
		(start 141.601105 91.2036)
		(end 143.010345 91.2036)
		(width 0.1905)
		(layer "B.Cu")
		(net "ANT_OFF")
	)
	(segment
		(start 139.352995 91.68141)
		(end 141.601105 91.68141)
		(width 0.1905)
		(layer "B.Cu")
		(net "ANT_OFF")
	)
	(segment
		(start 152.401105 93.84359)
		(end 152.401105 92.58844)
		(width 0.1905)
		(layer "F.Cu")
		(net "ANT_DET")
	)
	(segment
		(start 139.851105 90.9036)
		(end 140.051105 91.1036)
		(width 0.1905)
		(layer "F.Cu")
		(net "ANT_DET")
	)
	(segment
		(start 139.851105 90.9036)
		(end 139.851105 90.0036)
		(width 0.1905)
		(layer "F.Cu")
		(net "ANT_DET")
	)
	(segment
		(start 152.401105 92.58844)
		(end 152.403465 92.58608)
		(width 0.1905)
		(layer "F.Cu")
		(net "ANT_DET")
	)
	(segment
		(start 140.051105 91.1036)
		(end 140.101105 91.1036)
		(width 0.1905)
		(layer "F.Cu")
		(net "ANT_DET")
	)
	(via
		(at 140.101105 91.1036)
		(size 0.4064)
		(drill 0.254)
		(layers "F.Cu" "B.Cu")
		(net "ANT_DET")
	)
	(via
		(at 152.403465 92.58608)
		(size 0.4064)
		(drill 0.254)
		(layers "F.Cu" "B.Cu")
		(net "ANT_DET")
	)
	(segment
		(start 143.775035 91.3036)
		(end 151.701105 91.3036)
		(width 0.1905)
		(layer "B.Cu")
		(net "ANT_DET")
	)
	(segment
		(start 151.701105 91.3036)
		(end 152.403465 92.00596)
		(width 0.1905)
		(layer "B.Cu")
		(net "ANT_DET")
	)
	(segment
		(start 152.403465 92.58608)
		(end 152.403465 92.00596)
		(width 0.1905)
		(layer "B.Cu")
		(net "ANT_DET")
	)
	(segment
		(start 143.775035 91.3036)
		(end 143.775035 90.7036)
		(width 0.1905)
		(layer "B.Cu")
		(net "ANT_DET")
	)
	(segment
		(start 140.101105 90.7036)
		(end 143.775035 90.7036)
		(width 0.1905)
		(layer "B.Cu")
		(net "ANT_DET")
	)
	(segment
		(start 140.101105 91.1036)
		(end 140.101105 90.7036)
		(width 0.1905)
		(layer "B.Cu")
		(net "ANT_DET")
	)
	(segment
		(start 147.901105 119.04458)
		(end 147.901105 118.6286)
		(width 0.1905)
		(layer "F.Cu")
		(net "NetJ1_46")
	)
	(via
		(at 148.195935 119.75637)
		(size 0.4064)
		(drill 0.254)
		(layers "F.Cu" "B.Cu")
		(net "NetJ1_46")
	)
	(arc
		(start 148.195419 119.75585)
		(mid 147.977589 119.429459)
		(end 147.901104 119.04458)
		(width 0.1778)
		(layer "F.Cu")
		(net "NetJ1_46")
	)
	(segment
		(start 146.901105 119.9036)
		(end 146.901285 119.90342)
		(width 0.1905)
		(layer "B.Cu")
		(net "NetJ1_46")
	)
	(segment
		(start 146.201105 122.83249)
		(end 146.201105 121.2036)
		(width 0.1905)
		(layer "B.Cu")
		(net "NetJ1_46")
	)
	(segment
		(start 146.625115 120.17958)
		(end 146.625365 120.17933)
		(width 0.1905)
		(layer "B.Cu")
		(net "NetJ1_46")
	)
	(segment
		(start 146.625365 120.17933)
		(end 146.901105 119.9036)
		(width 0.1905)
		(layer "B.Cu")
		(net "NetJ1_46")
	)
	(segment
		(start 147.256535 119.75637)
		(end 148.195935 119.75637)
		(width 0.1905)
		(layer "B.Cu")
		(net "NetJ1_46")
	)
	(segment
		(start 146.507105 124.4786)
		(end 146.507105 123.57124)
		(width 0.1905)
		(layer "B.Cu")
		(net "NetJ1_46")
	)
	(arc
		(start 146.201105 121.2036)
		(mid 146.3113 120.649435)
		(end 146.625119 120.179585)
		(width 0.1778)
		(layer "B.Cu")
		(net "NetJ1_46")
	)
	(arc
		(start 146.376661 123.256344)
		(mid 146.246723 123.061878)
		(end 146.201095 122.83249)
		(width 0.1778)
		(layer "B.Cu")
		(net "NetJ1_46")
	)
	(arc
		(start 146.376671 123.256344)
		(mid 146.473206 123.40082)
		(end 146.507105 123.57124)
		(width 0.1905)
		(layer "B.Cu")
		(net "NetJ1_46")
	)
	(arc
		(start 146.90128 119.903417)
		(mid 147.064292 119.794585)
		(end 147.256535 119.75637)
		(width 0.1778)
		(layer "B.Cu")
		(net "NetJ1_46")
	)
	(segment
		(start 149.251105 124.7286)
		(end 149.251105 120.7472)
		(width 0.1905)
		(layer "F.Cu")
		(net "NetJ1_35")
	)
	(segment
		(start 148.901105 119.37044)
		(end 148.901105 118.6286)
		(width 0.1905)
		(layer "F.Cu")
		(net "NetJ1_35")
	)
	(segment
		(start 149.251105 120.7472)
		(end 149.251105 120.36338)
		(width 0.1905)
		(layer "F.Cu")
		(net "NetJ1_35")
	)
	(arc
		(start 148.999458 119.755851)
		(mid 148.926081 119.569321)
		(end 148.901105 119.37044)
		(width 0.1778)
		(layer "F.Cu")
		(net "NetJ1_35")
	)
	(arc
		(start 148.999463 119.755862)
		(mid 149.07735 119.845329)
		(end 149.142171 119.944671)
		(width 0.1778)
		(layer "F.Cu")
		(net "NetJ1_35")
	)
	(arc
		(start 149.142171 119.944671)
		(mid 149.223426 120.147057)
		(end 149.251105 120.363381)
		(width 0.1778)
		(layer "F.Cu")
		(net "NetJ1_35")
	)
	(via
		(at 158.501105 105.69359)
		(size 0.4064)
		(drill 0.254)
		(layers "F.Cu" "B.Cu")
		(net "SDA")
	)
	(segment
		(start 156.701105 110.9036)
		(end 156.701105 105.8036)
		(width 0.1905)
		(layer "B.Cu")
		(net "SDA")
	)
	(segment
		(start 158.697985 104.00463)
		(end 158.960735 104.26738)
		(width 0.1905)
		(layer "B.Cu")
		(net "SDA")
	)
	(segment
		(start 156.001105 117.0036)
		(end 156.001105 111.6036)
		(width 0.1905)
		(layer "B.Cu")
		(net "SDA")
	)
	(segment
		(start 157.201105 105.3036)
		(end 157.201105 104.9036)
		(width 0.1905)
		(layer "B.Cu")
		(net "SDA")
	)
	(segment
		(start 150.743035 118.43062)
		(end 151.170055 118.0036)
		(width 0.1905)
		(layer "B.Cu")
		(net "SDA")
	)
	(segment
		(start 155.001105 118.0036)
		(end 156.001105 117.0036)
		(width 0.1905)
		(layer "B.Cu")
		(net "SDA")
	)
	(segment
		(start 158.100075 104.00463)
		(end 158.697985 104.00463)
		(width 0.1905)
		(layer "B.Cu")
		(net "SDA")
	)
	(segment
		(start 157.201105 104.9036)
		(end 158.100075 104.00463)
		(width 0.1905)
		(layer "B.Cu")
		(net "SDA")
	)
	(segment
		(start 156.701105 105.8036)
		(end 157.201105 105.3036)
		(width 0.1905)
		(layer "B.Cu")
		(net "SDA")
	)
	(segment
		(start 147.507105 121.4976)
		(end 150.574085 118.43062)
		(width 0.1905)
		(layer "B.Cu")
		(net "SDA")
	)
	(segment
		(start 156.001105 111.6036)
		(end 156.701105 110.9036)
		(width 0.1905)
		(layer "B.Cu")
		(net "SDA")
	)
	(segment
		(start 147.507105 124.4786)
		(end 147.507105 121.4976)
		(width 0.1905)
		(layer "B.Cu")
		(net "SDA")
	)
	(segment
		(start 158.960735 105.23397)
		(end 158.960735 104.26738)
		(width 0.1905)
		(layer "B.Cu")
		(net "SDA")
	)
	(segment
		(start 151.170055 118.0036)
		(end 155.001105 118.0036)
		(width 0.1905)
		(layer "B.Cu")
		(net "SDA")
	)
	(segment
		(start 158.501105 105.69359)
		(end 158.960735 105.23397)
		(width 0.1905)
		(layer "B.Cu")
		(net "SDA")
	)
	(segment
		(start 150.574085 118.43062)
		(end 150.743035 118.43062)
		(width 0.1905)
		(layer "B.Cu")
		(net "SDA")
	)
	(via
		(at 158.501105 104.59359)
		(size 0.4064)
		(drill 0.254)
		(layers "F.Cu" "B.Cu")
		(net "SCL")
	)
	(segment
		(start 154.601105 119.1036)
		(end 156.501105 117.2036)
		(width 0.1905)
		(layer "B.Cu")
		(net "SCL")
	)
	(segment
		(start 156.501105 117.2036)
		(end 156.501105 111.6036)
		(width 0.1905)
		(layer "B.Cu")
		(net "SCL")
	)
	(segment
		(start 148.007105 121.5976)
		(end 150.501105 119.1036)
		(width 0.1905)
		(layer "B.Cu")
		(net "SCL")
	)
	(segment
		(start 156.501105 111.6036)
		(end 157.101105 111.0036)
		(width 0.1905)
		(layer "B.Cu")
		(net "SCL")
	)
	(segment
		(start 157.101105 105.99359)
		(end 158.501105 104.59359)
		(width 0.1905)
		(layer "B.Cu")
		(net "SCL")
	)
	(segment
		(start 148.007105 124.4786)
		(end 148.007105 121.5976)
		(width 0.1905)
		(layer "B.Cu")
		(net "SCL")
	)
	(segment
		(start 150.501105 119.1036)
		(end 154.601105 119.1036)
		(width 0.1905)
		(layer "B.Cu")
		(net "SCL")
	)
	(segment
		(start 157.101105 111.0036)
		(end 157.101105 105.99359)
		(width 0.1905)
		(layer "B.Cu")
		(net "SCL")
	)
	(segment
		(start 141.251105 124.7286)
		(end 141.251105 122.1536)
		(width 0.1905)
		(layer "F.Cu")
		(net "NetJ1_67")
	)
	(segment
		(start 144.401105 119.0036)
		(end 144.401105 118.3286)
		(width 0.1905)
		(layer "F.Cu")
		(net "NetJ1_67")
	)
	(segment
		(start 141.251105 122.1536)
		(end 144.401105 119.0036)
		(width 0.1905)
		(layer "F.Cu")
		(net "NetJ1_67")
	)
	(segment
		(start 145.576705 118.353)
		(end 145.601105 118.3286)
		(width 0.1905)
		(layer "F.Cu")
		(net "NetJ1_50")
	)
	(segment
		(start 145.552315 119.24201)
		(end 145.576705 119.21762)
		(width 0.1905)
		(layer "F.Cu")
		(net "NetJ1_50")
	)
	(segment
		(start 145.576705 119.21762)
		(end 145.576705 118.353)
		(width 0.1905)
		(layer "F.Cu")
		(net "NetJ1_50")
	)
	(via
		(at 145.552315 119.24201)
		(size 0.4064)
		(drill 0.254)
		(layers "F.Cu" "B.Cu")
		(net "NetJ1_50")
	)
	(segment
		(start 145.501105 121.1036)
		(end 145.504105 121.1066)
		(width 0.2032)
		(layer "B.Cu")
		(net "NetJ1_50")
	)
	(segment
		(start 145.501105 119.29323)
		(end 145.552315 119.24201)
		(width 0.1905)
		(layer "B.Cu")
		(net "NetJ1_50")
	)
	(segment
		(start 145.504105 124.4756)
		(end 145.504105 121.1066)
		(width 0.1905)
		(layer "B.Cu")
		(net "NetJ1_50")
	)
	(segment
		(start 145.501105 121.1036)
		(end 145.501105 119.29323)
		(width 0.1905)
		(layer "B.Cu")
		(net "NetJ1_50")
	)
	(segment
		(start 145.504105 124.4756)
		(end 145.507105 124.4786)
		(width 0.2032)
		(layer "B.Cu")
		(net "NetJ1_50")
	)
	(segment
		(start 139.839735 85.9013)
		(end 139.851105 85.91268)
		(width 0.1905)
		(layer "F.Cu")
		(net "NetQ1_1")
	)
	(segment
		(start 139.851105 86.8036)
		(end 139.851105 85.91268)
		(width 0.1905)
		(layer "F.Cu")
		(net "NetQ1_1")
	)
	(segment
		(start 143.031275 89.8536)
		(end 144.101105 89.8536)
		(width 0.254)
		(layer "F.Cu")
		(net "NetQ1_1")
	)
	(via
		(at 139.839735 85.9013)
		(size 0.4064)
		(drill 0.254)
		(layers "F.Cu" "B.Cu")
		(net "NetQ1_1")
	)
	(via
		(at 142.898495 90.03868)
		(size 0.4064)
		(drill 0.254)
		(layers "F.Cu" "B.Cu")
		(net "NetQ1_1")
	)
	(segment
		(start 142.692445 89.99494)
		(end 142.854755 89.99494)
		(width 0.1905)
		(layer "B.Cu")
		(net "NetQ1_1")
	)
	(segment
		(start 139.839735 87.14223)
		(end 142.692445 89.99494)
		(width 0.1905)
		(layer "B.Cu")
		(net "NetQ1_1")
	)
	(segment
		(start 142.854755 89.99494)
		(end 142.898495 90.03868)
		(width 0.1905)
		(layer "B.Cu")
		(net "NetQ1_1")
	)
	(segment
		(start 139.839735 87.14223)
		(end 139.839735 85.9013)
		(width 0.1905)
		(layer "B.Cu")
		(net "NetQ1_1")
	)
	(segment
		(start 146.151105 88.7286)
		(end 146.201105 88.6786)
		(width 0.381)
		(layer "F.Cu")
		(net "NetQ1_3")
	)
	(segment
		(start 146.151105 90.7536)
		(end 146.151105 88.7286)
		(width 0.381)
		(layer "F.Cu")
		(net "NetQ1_3")
	)
	(segment
		(start 146.551105 91.2036)
		(end 149.501105 91.2036)
		(width 0.381)
		(layer "F.Cu")
		(net "NetQ1_3")
	)
	(segment
		(start 146.101105 90.8036)
		(end 146.151105 90.7536)
		(width 0.381)
		(layer "F.Cu")
		(net "NetQ1_3")
	)
	(segment
		(start 146.151105 90.8036)
		(end 146.551105 91.2036)
		(width 0.381)
		(layer "F.Cu")
		(net "NetQ1_3")
	)
	(segment
		(start 154.199475 109.61572)
		(end 154.199475 109.61572)
		(width 0.16078)
		(layer "F.Cu")
		(net "USB_D_P")
	)
	(segment
		(start 154.199475 110.63788)
		(end 154.199475 109.61572)
		(width 0.16078)
		(layer "F.Cu")
		(net "USB_D_P")
	)
	(segment
		(start 151.401105 117.62076)
		(end 151.401105 115.3036)
		(width 0.16078)
		(layer "F.Cu")
		(net "USB_D_P")
	)
	(segment
		(start 156.156495 124.63399)
		(end 156.251105 124.7286)
		(width 0.16078)
		(layer "F.Cu")
		(net "USB_D_P")
	)
	(segment
		(start 156.144995 123.88142)
		(end 156.144995 121.57073)
		(width 0.16078)
		(layer "F.Cu")
		(net "USB_D_P")
	)
	(segment
		(start 156.156495 124.63399)
		(end 156.156495 123.89292)
		(width 0.16078)
		(layer "F.Cu")
		(net "USB_D_P")
	)
	(segment
		(start 151.896085 114.10862)
		(end 153.374035 112.63067)
		(width 0.16078)
		(layer "F.Cu")
		(net "USB_D_P")
	)
	(segment
		(start 154.199475 109.61572)
		(end 154.199475 109.61571)
		(width 0.16078)
		(layer "F.Cu")
		(net "USB_D_P")
	)
	(segment
		(start 154.802875 119.39839)
		(end 155.557935 120.15345)
		(width 0.16078)
		(layer "F.Cu")
		(net "USB_D_P")
	)
	(segment
		(start 154.532175 108.81253)
		(end 154.601105 108.74359)
		(width 0.16078)
		(layer "F.Cu")
		(net "USB_D_P")
	)
	(segment
		(start 156.144995 123.88142)
		(end 156.156495 123.89292)
		(width 0.16078)
		(layer "F.Cu")
		(net "USB_D_P")
	)
	(segment
		(start 153.079135 118.71582)
		(end 153.155015 118.71582)
		(width 0.16078)
		(layer "F.Cu")
		(net "USB_D_P")
	)
	(arc
		(start 151.601104 118.103601)
		(mid 151.453083 117.882072)
		(end 151.401105 117.62076)
		(width 0.16078)
		(layer "F.Cu")
		(net "USB_D_P")
	)
	(arc
		(start 151.401105 115.3036)
		(mid 151.529746 114.65688)
		(end 151.896083 114.108618)
		(width 0.16078)
		(layer "F.Cu")
		(net "USB_D_P")
	)
	(arc
		(start 153.079135 118.71582)
		(mid 152.279231 118.556709)
		(end 151.601105 118.1036)
		(width 0.16078)
		(layer "F.Cu")
		(net "USB_D_P")
	)
	(arc
		(start 155.557937 120.153448)
		(mid 155.992423 120.803703)
		(end 156.144994 121.57073)
		(width 0.16078)
		(layer "F.Cu")
		(net "USB_D_P")
	)
	(arc
		(start 154.199475 110.63788)
		(mid 153.984951 111.716366)
		(end 153.374037 112.630662)
		(width 0.16078)
		(layer "F.Cu")
		(net "USB_D_P")
	)
	(arc
		(start 154.281495 109.41772)
		(mid 154.346644 109.090193)
		(end 154.532174 108.812529)
		(width 0.16078)
		(layer "F.Cu")
		(net "USB_D_P")
	)
	(arc
		(start 154.281495 109.41772)
		(mid 154.260181 109.524875)
		(end 154.199482 109.615717)
		(width 0.16078)
		(layer "F.Cu")
		(net "USB_D_P")
	)
	(arc
		(start 153.155015 118.71582)
		(mid 154.046832 118.893213)
		(end 154.802878 119.398387)
		(width 0.16078)
		(layer "F.Cu")
		(net "USB_D_P")
	)
	(segment
		(start 153.075985 119.0036)
		(end 153.152575 119.0036)
		(width 0.16078)
		(layer "F.Cu")
		(net "USB_D_N")
	)
	(segment
		(start 151.395885 118.30536)
		(end 151.399845 118.30932)
		(width 0.16078)
		(layer "F.Cu")
		(net "USB_D_N")
	)
	(segment
		(start 155.857215 123.88142)
		(end 155.857215 121.57542)
		(width 0.16078)
		(layer "F.Cu")
		(net "USB_D_N")
	)
	(segment
		(start 153.911695 110.63392)
		(end 153.911695 109.61572)
		(width 0.16078)
		(layer "F.Cu")
		(net "USB_D_N")
	)
	(segment
		(start 155.845715 124.63399)
		(end 155.845715 123.89292)
		(width 0.16078)
		(layer "F.Cu")
		(net "USB_D_N")
	)
	(segment
		(start 151.691745 113.90598)
		(end 153.167755 112.42997)
		(width 0.16078)
		(layer "F.Cu")
		(net "USB_D_N")
	)
	(segment
		(start 155.845715 123.89292)
		(end 155.857215 123.88142)
		(width 0.16078)
		(layer "F.Cu")
		(net "USB_D_N")
	)
	(segment
		(start 151.113325 117.62321)
		(end 151.113325 115.3024)
		(width 0.16078)
		(layer "F.Cu")
		(net "USB_D_N")
	)
	(segment
		(start 154.601105 119.6036)
		(end 155.351125 120.35362)
		(width 0.16078)
		(layer "F.Cu")
		(net "USB_D_N")
	)
	(segment
		(start 153.748595 109.34108)
		(end 153.832835 109.42532)
		(width 0.16078)
		(layer "F.Cu")
		(net "USB_D_N")
	)
	(segment
		(start 155.751105 124.7286)
		(end 155.845715 124.63399)
		(width 0.16078)
		(layer "F.Cu")
		(net "USB_D_N")
	)
	(arc
		(start 153.911695 110.63392)
		(mid 153.718349 111.605936)
		(end 153.167746 112.429971)
		(width 0.16078)
		(layer "F.Cu")
		(net "USB_D_N")
	)
	(arc
		(start 155.351128 120.353617)
		(mid 155.725688 120.914185)
		(end 155.857215 121.57542)
		(width 0.16078)
		(layer "F.Cu")
		(net "USB_D_N")
	)
	(arc
		(start 153.832831 109.425324)
		(mid 153.891199 109.512678)
		(end 153.911696 109.61572)
		(width 0.16078)
		(layer "F.Cu")
		(net "USB_D_N")
	)
	(arc
		(start 153.152575 119.00359)
		(mid 153.936513 119.159525)
		(end 154.601104 119.603591)
		(width 0.16078)
		(layer "F.Cu")
		(net "USB_D_N")
	)
	(arc
		(start 153.075985 119.0036)
		(mid 152.168865 118.823163)
		(end 151.399845 118.30932)
		(width 0.16078)
		(layer "F.Cu")
		(net "USB_D_N")
	)
	(arc
		(start 151.395882 118.305363)
		(mid 151.186759 117.992389)
		(end 151.113325 117.62321)
		(width 0.16078)
		(layer "F.Cu")
		(net "USB_D_N")
	)
	(arc
		(start 151.113325 115.3024)
		(mid 151.26365 114.546665)
		(end 151.691739 113.905984)
		(width 0.16078)
		(layer "F.Cu")
		(net "USB_D_N")
	)
	(arc
		(start 153.748591 109.341074)
		(mid 153.565425 109.066946)
		(end 153.501105 108.74359)
		(width 0.16078)
		(layer "F.Cu")
		(net "USB_D_N")
	)
	(segment
		(start 148.901105 117.7786)
		(end 148.901105 112.26546)
		(width 0.1905)
		(layer "F.Cu")
		(net "TP1")
	)
	(segment
		(start 149.001105 112.16546)
		(end 149.001105 112.1036)
		(width 0.1905)
		(layer "F.Cu")
		(net "TP1")
	)
	(segment
		(start 148.901105 112.26546)
		(end 149.001105 112.16546)
		(width 0.1905)
		(layer "F.Cu")
		(net "TP1")
	)
	(segment
		(start 147.901105 117.7786)
		(end 148.901105 117.7786)
		(width 0.1905)
		(layer "F.Cu")
		(net "TP1")
	)
	(via
		(at 158.501105 95.79359)
		(size 0.4064)
		(drill 0.254)
		(layers "F.Cu" "B.Cu")
		(net "TP1")
	)
	(via
		(at 149.001105 112.1036)
		(size 0.4064)
		(drill 0.254)
		(layers "F.Cu" "B.Cu")
		(net "TP1")
	)
	(segment
		(start 151.145055 97.15965)
		(end 151.301105 97.0036)
		(width 0.1905)
		(layer "B.Cu")
		(net "TP1")
	)
	(segment
		(start 158.235045 96.05965)
		(end 158.501105 95.79359)
		(width 0.1905)
		(layer "B.Cu")
		(net "TP1")
	)
	(segment
		(start 150.401105 110.45043)
		(end 150.401105 98.9557)
		(width 0.1905)
		(layer "B.Cu")
		(net "TP1")
	)
	(segment
		(start 151.783945 96.8036)
		(end 156.438995 96.8036)
		(width 0.1905)
		(layer "B.Cu")
		(net "TP1")
	)
	(segment
		(start 149.622085 111.84638)
		(end 149.964865 111.5036)
		(width 0.1905)
		(layer "B.Cu")
		(net "TP1")
	)
	(arc
		(start 158.235046 96.059651)
		(mid 157.411011 96.610254)
		(end 156.438995 96.8036)
		(width 0.1778)
		(layer "B.Cu")
		(net "TP1")
	)
	(arc
		(start 150.401105 98.9557)
		(mid 150.594451 97.983684)
		(end 151.145054 97.159649)
		(width 0.1778)
		(layer "B.Cu")
		(net "TP1")
	)
	(arc
		(start 149.622086 111.846381)
		(mid 149.337177 112.036751)
		(end 149.001105 112.1036)
		(width 0.1778)
		(layer "B.Cu")
		(net "TP1")
	)
	(arc
		(start 150.401105 110.45043)
		(mid 150.28773 111.020403)
		(end 149.964867 111.503602)
		(width 0.1778)
		(layer "B.Cu")
		(net "TP1")
	)
	(arc
		(start 151.301104 97.003599)
		(mid 151.522633 96.855578)
		(end 151.783945 96.8036)
		(width 0.1778)
		(layer "B.Cu")
		(net "TP1")
	)
	(segment
		(start 146.484945 117.4786)
		(end 146.517355 117.44619)
		(width 0.1905)
		(layer "F.Cu")
		(net "RST_GPS")
	)
	(segment
		(start 144.401105 117.4786)
		(end 145.601105 117.4786)
		(width 0.1905)
		(layer "F.Cu")
		(net "RST_GPS")
	)
	(segment
		(start 145.601105 117.4786)
		(end 146.484945 117.4786)
		(width 0.1905)
		(layer "F.Cu")
		(net "RST_GPS")
	)
	(via
		(at 158.501105 100.19359)
		(size 0.4064)
		(drill 0.254)
		(layers "F.Cu" "B.Cu")
		(net "RST_GPS")
	)
	(via
		(at 146.517355 117.44619)
		(size 0.4064)
		(drill 0.254)
		(layers "F.Cu" "B.Cu")
		(net "RST_GPS")
	)
	(segment
		(start 146.517355 117.44619)
		(end 153.758515 117.44619)
		(width 0.1905)
		(layer "B.Cu")
		(net "RST_GPS")
	)
	(segment
		(start 155.201105 116.0036)
		(end 155.201105 103.98651)
		(width 0.1905)
		(layer "B.Cu")
		(net "RST_GPS")
	)
	(segment
		(start 153.758515 117.44619)
		(end 155.201105 116.0036)
		(width 0.1905)
		(layer "B.Cu")
		(net "RST_GPS")
	)
	(segment
		(start 158.501105 100.68651)
		(end 158.501105 100.19359)
		(width 0.1905)
		(layer "B.Cu")
		(net "RST_GPS")
	)
	(segment
		(start 155.201105 103.98651)
		(end 158.501105 100.68651)
		(width 0.1905)
		(layer "B.Cu")
		(net "RST_GPS")
	)
	(segment
		(start 154.630595 87.06706)
		(end 154.631465 87.06619)
		(width 0.1905)
		(layer "F.Cu")
		(net "RF_ANT")
	)
	(segment
		(start 154.630595 88.43974)
		(end 154.630595 87.06706)
		(width 0.1905)
		(layer "F.Cu")
		(net "RF_ANT")
	)
	(segment
		(start 154.617485 88.45284)
		(end 154.630595 88.43974)
		(width 0.1905)
		(layer "F.Cu")
		(net "RF_ANT")
	)
	(segment
		(start 154.601105 90.67504)
		(end 154.601105 89.54204)
		(width 0.1905)
		(layer "F.Cu")
		(net "RF_ANT")
	)
	(segment
		(start 154.617485 89.52566)
		(end 154.617485 88.45284)
		(width 0.1905)
		(layer "F.Cu")
		(net "RF_ANT")
	)
	(segment
		(start 154.601105 89.54204)
		(end 154.617485 89.52566)
		(width 0.1905)
		(layer "F.Cu")
		(net "RF_ANT")
	)
	(segment
		(start 143.751105 124.7286)
		(end 143.751105 123.4148)
		(width 0.254)
		(layer "F.Cu")
		(net "GND")
	)
	(segment
		(start 157.251105 124.7286)
		(end 157.251105 122.1467)
		(width 0.3048)
		(layer "F.Cu")
		(net "GND")
	)
	(segment
		(start 152.701105 122.4036)
		(end 152.751105 122.4536)
		(width 0.254)
		(layer "F.Cu")
		(net "GND")
	)
	(segment
		(start 138.930175 85.01582)
		(end 139.760325 85.01582)
		(width 0.1905)
		(layer "F.Cu")
		(net "GND")
	)
	(segment
		(start 151.079665 111.5036)
		(end 151.985765 111.5036)
		(width 0.508)
		(layer "F.Cu")
		(net "GND")
	)
	(segment
		(start 151.327285 109.79325)
		(end 151.327285 108.76978)
		(width 0.508)
		(layer "F.Cu")
		(net "GND")
	)
	(segment
		(start 140.701105 112.9036)
		(end 141.446295 112.9036)
		(width 0.3048)
		(layer "F.Cu")
		(net "GND")
	)
	(segment
		(start 145.921125 110.48468)
		(end 145.924795 110.481)
		(width 0.508)
		(layer "F.Cu")
		(net "GND")
	)
	(segment
		(start 148.251105 124.7286)
		(end 148.251105 122.89484)
		(width 0.254)
		(layer "F.Cu")
		(net "GND")
	)
	(segment
		(start 139.251105 124.7286)
		(end 139.251105 122.5036)
		(width 0.254)
		(layer "F.Cu")
		(net "GND")
	)
	(segment
		(start 155.101105 121.64484)
		(end 155.101105 121.6036)
		(width 0.254)
		(layer "F.Cu")
		(net "GND")
	)
	(segment
		(start 145.823925 109.79325)
		(end 145.823925 108.76641)
		(width 0.508)
		(layer "F.Cu")
		(net "GND")
	)
	(segment
		(start 149.751105 122.5536)
		(end 149.801105 122.5036)
		(width 0.254)
		(layer "F.Cu")
		(net "GND")
	)
	(segment
		(start 139.751105 124.7286)
		(end 139.751105 122.4036)
		(width 0.254)
		(layer "F.Cu")
		(net "GND")
	)
	(segment
		(start 146.751105 122.6536)
		(end 146.801105 122.6036)
		(width 0.254)
		(layer "F.Cu")
		(net "GND")
	)
	(segment
		(start 142.601105 88.9036)
		(end 142.901105 88.6036)
		(width 0.1905)
		(layer "F.Cu")
		(net "GND")
	)
	(segment
		(start 156.601105 123.11574)
		(end 156.751105 123.26574)
		(width 0.254)
		(layer "F.Cu")
		(net "GND")
	)
	(segment
		(start 145.801105 108.74359)
		(end 145.823925 108.76641)
		(width 0.508)
		(layer "F.Cu")
		(net "GND")
	)
	(segment
		(start 155.683665 109.85944)
		(end 155.701105 109.84199)
		(width 0.508)
		(layer "F.Cu")
		(net "GND")
	)
	(segment
		(start 145.801105 111.4036)
		(end 145.921125 111.28358)
		(width 0.508)
		(layer "F.Cu")
		(net "GND")
	)
	(segment
		(start 142.806175 113.3036)
		(end 143.522545 113.3036)
		(width 0.3048)
		(layer "F.Cu")
		(net "GND")
	)
	(segment
		(start 138.851105 86.8036)
		(end 138.851105 86.05562)
		(width 0.1905)
		(layer "F.Cu")
		(net "GND")
	)
	(segment
		(start 152.386055 108.75865)
		(end 152.401105 108.74359)
		(width 0.508)
		(layer "F.Cu")
		(net "GND")
	)
	(segment
		(start 148.251105 122.89484)
		(end 148.601105 122.54484)
		(width 0.254)
		(layer "F.Cu")
		(net "GND")
	)
	(segment
		(start 141.446295 112.93855)
		(end 141.446295 112.9036)
		(width 0.3048)
		(layer "F.Cu")
		(net "GND")
	)
	(segment
		(start 156.894805 121.7904)
		(end 157.251105 122.1467)
		(width 0.3048)
		(layer "F.Cu")
		(net "GND")
	)
	(segment
		(start 156.555585 121.61008)
		(end 156.583075 121.61008)
		(width 0.3048)
		(layer "F.Cu")
		(net "GND")
	)
	(segment
		(start 152.938435 115.40395)
		(end 153.001105 115.40395)
		(width 0.1905)
		(layer "F.Cu")
		(net "GND")
	)
	(segment
		(start 143.801105 123.3648)
		(end 143.801105 122.2036)
		(width 0.254)
		(layer "F.Cu")
		(net "GND")
	)
	(segment
		(start 140.251105 124.7286)
		(end 140.251105 122.4036)
		(width 0.254)
		(layer "F.Cu")
		(net "GND")
	)
	(segment
		(start 138.616245 85.82075)
		(end 138.851105 86.05562)
		(width 0.1905)
		(layer "F.Cu")
		(net "GND")
	)
	(segment
		(start 155.701105 109.84199)
		(end 155.701105 108.74359)
		(width 0.508)
		(layer "F.Cu")
		(net "GND")
	)
	(segment
		(start 142.540665 88.25623)
		(end 142.601105 88.19579)
		(width 0.1905)
		(layer "F.Cu")
		(net "GND")
	)
	(segment
		(start 145.921125 111.28358)
		(end 145.921125 110.48468)
		(width 0.508)
		(layer "F.Cu")
		(net "GND")
	)
	(segment
		(start 151.301105 108.74359)
		(end 151.327285 108.76978)
		(width 0.508)
		(layer "F.Cu")
		(net "GND")
	)
	(segment
		(start 142.901105 88.6036)
		(end 143.435565 88.6036)
		(width 0.1905)
		(layer "F.Cu")
		(net "GND")
	)
	(segment
		(start 152.386055 109.88148)
		(end 152.386055 108.75865)
		(width 0.508)
		(layer "F.Cu")
		(net "GND")
	)
	(segment
		(start 143.751105 123.4148)
		(end 143.801105 123.3648)
		(width 0.254)
		(layer "F.Cu")
		(net "GND")
	)
	(segment
		(start 152.751105 124.7286)
		(end 152.751105 122.4536)
		(width 0.254)
		(layer "F.Cu")
		(net "GND")
	)
	(segment
		(start 151.985765 111.5036)
		(end 152.003765 111.48561)
		(width 0.508)
		(layer "F.Cu")
		(net "GND")
	)
	(segment
		(start 151.201105 122.4036)
		(end 151.251105 122.4536)
		(width 0.254)
		(layer "F.Cu")
		(net "GND")
	)
	(segment
		(start 146.751105 124.7286)
		(end 146.751105 122.6536)
		(width 0.254)
		(layer "F.Cu")
		(net "GND")
	)
	(segment
		(start 156.583075 121.61008)
		(end 156.763395 121.7904)
		(width 0.3048)
		(layer "F.Cu")
		(net "GND")
	)
	(segment
		(start 145.251105 124.7286)
		(end 145.251105 122.6036)
		(width 0.254)
		(layer "F.Cu")
		(net "GND")
	)
	(segment
		(start 149.751105 124.7286)
		(end 149.751105 122.5536)
		(width 0.254)
		(layer "F.Cu")
		(net "GND")
	)
	(segment
		(start 139.760325 85.01582)
		(end 139.772545 85.0036)
		(width 0.1905)
		(layer "F.Cu")
		(net "GND")
	)
	(segment
		(start 156.763395 121.7904)
		(end 156.894805 121.7904)
		(width 0.3048)
		(layer "F.Cu")
		(net "GND")
	)
	(segment
		(start 153.001105 116.3036)
		(end 153.001105 115.40395)
		(width 0.1905)
		(layer "F.Cu")
		(net "GND")
	)
	(segment
		(start 148.879665 110.5036)
		(end 149.001105 110.62504)
		(width 0.508)
		(layer "F.Cu")
		(net "GND")
	)
	(segment
		(start 155.101105 121.64484)
		(end 155.251105 121.79484)
		(width 0.254)
		(layer "F.Cu")
		(net "GND")
	)
	(segment
		(start 151.251105 124.7286)
		(end 151.251105 122.4536)
		(width 0.254)
		(layer "F.Cu")
		(net "GND")
	)
	(segment
		(start 142.601105 88.19579)
		(end 142.601105 87.3286)
		(width 0.1905)
		(layer "F.Cu")
		(net "GND")
	)
	(segment
		(start 156.601105 123.11574)
		(end 156.601105 122.3036)
		(width 0.254)
		(layer "F.Cu")
		(net "GND")
	)
	(segment
		(start 148.601105 122.54484)
		(end 148.601105 122.5036)
		(width 0.254)
		(layer "F.Cu")
		(net "GND")
	)
	(segment
		(start 140.201105 124.7286)
		(end 140.251105 124.7286)
		(width 0.254)
		(layer "F.Cu")
		(net "GND")
	)
	(segment
		(start 155.251105 124.7286)
		(end 155.251105 121.79484)
		(width 0.254)
		(layer "F.Cu")
		(net "GND")
	)
	(segment
		(start 156.751105 124.7286)
		(end 156.751105 123.26574)
		(width 0.254)
		(layer "F.Cu")
		(net "GND")
	)
	(segment
		(start 142.806175 113.3307)
		(end 142.806175 113.3036)
		(width 0.3048)
		(layer "F.Cu")
		(net "GND")
	)
	(segment
		(start 149.001105 111.4036)
		(end 149.001105 110.62504)
		(width 0.508)
		(layer "F.Cu")
		(net "GND")
	)
	(via
		(at 141.201105 100.3036)
		(size 0.4064)
		(drill 0.254)
		(layers "F.Cu" "B.Cu")
		(net "GND")
	)
	(via
		(at 152.386055 109.88148)
		(size 0.4064)
		(drill 0.254)
		(layers "F.Cu" "B.Cu")
		(net "GND")
	)
	(via
		(at 156.601105 122.3036)
		(size 0.4064)
		(drill 0.254)
		(layers "F.Cu" "B.Cu")
		(net "GND")
	)
	(via
		(at 149.001105 111.4036)
		(size 0.4064)
		(drill 0.254)
		(layers "F.Cu" "B.Cu")
		(net "GND")
	)
	(via
		(at 157.468105 88.2836)
		(size 0.4064)
		(drill 0.254)
		(layers "F.Cu" "B.Cu")
		(net "GND")
	)
	(via
		(at 158.484105 89.2996)
		(size 0.4064)
		(drill 0.254)
		(layers "F.Cu" "B.Cu")
		(net "GND")
	)
	(via
		(at 145.801105 111.4036)
		(size 0.4064)
		(drill 0.254)
		(layers "F.Cu" "B.Cu")
		(net "GND")
	)
	(via
		(at 147.501105 106.60358)
		(size 0.4064)
		(drill 0.254)
		(layers "F.Cu" "B.Cu")
		(net "GND")
	)
	(via
		(at 158.484105 93.3636)
		(size 0.4064)
		(drill 0.254)
		(layers "F.Cu" "B.Cu")
		(net "GND")
	)
	(via
		(at 155.436105 89.2996)
		(size 0.4064)
		(drill 0.254)
		(layers "F.Cu" "B.Cu")
		(net "GND")
	)
	(via
		(at 141.201105 104.44357)
		(size 0.4064)
		(drill 0.254)
		(layers "F.Cu" "B.Cu")
		(net "GND")
	)
	(via
		(at 149.601105 106.54357)
		(size 0.4064)
		(drill 0.254)
		(layers "F.Cu" "B.Cu")
		(net "GND")
	)
	(via
		(at 147.501105 102.40359)
		(size 0.4064)
		(drill 0.254)
		(layers "F.Cu" "B.Cu")
		(net "GND")
	)
	(via
		(at 153.404105 91.3316)
		(size 0.4064)
		(drill 0.254)
		(layers "F.Cu" "B.Cu")
		(net "GND")
	)
	(via
		(at 156.452105 93.3636)
		(size 0.4064)
		(drill 0.254)
		(layers "F.Cu" "B.Cu")
		(net "GND")
	)
	(via
		(at 145.401105 106.54357)
		(size 0.4064)
		(drill 0.254)
		(layers "F.Cu" "B.Cu")
		(net "GND")
	)
	(via
		(at 158.484105 90.3156)
		(size 0.4064)
		(drill 0.254)
		(layers "F.Cu" "B.Cu")
		(net "GND")
	)
	(via
		(at 151.701105 104.44357)
		(size 0.4064)
		(drill 0.254)
		(layers "F.Cu" "B.Cu")
		(net "GND")
	)
	(via
		(at 153.801105 96.04359)
		(size 0.4064)
		(drill 0.254)
		(layers "F.Cu" "B.Cu")
		(net "GND")
	)
	(via
		(at 145.276105 90.3156)
		(size 0.4064)
		(drill 0.254)
		(layers "F.Cu" "B.Cu")
		(net "GND")
	)
	(via
		(at 151.701105 100.3036)
		(size 0.4064)
		(drill 0.254)
		(layers "F.Cu" "B.Cu")
		(net "GND")
	)
	(via
		(at 147.501105 96.1036)
		(size 0.4064)
		(drill 0.254)
		(layers "F.Cu" "B.Cu")
		(net "GND")
	)
	(via
		(at 156.452105 91.3316)
		(size 0.4064)
		(drill 0.254)
		(layers "F.Cu" "B.Cu")
		(net "GND")
	)
	(via
		(at 157.468105 86.2516)
		(size 0.4064)
		(drill 0.254)
		(layers "F.Cu" "B.Cu")
		(net "GND")
	)
	(via
		(at 154.420105 85.2356)
		(size 0.4064)
		(drill 0.254)
		(layers "F.Cu" "B.Cu")
		(net "GND")
	)
	(via
		(at 145.401105 98.14358)
		(size 0.4064)
		(drill 0.254)
		(layers "F.Cu" "B.Cu")
		(net "GND")
	)
	(via
		(at 157.468105 85.2356)
		(size 0.4064)
		(drill 0.254)
		(layers "F.Cu" "B.Cu")
		(net "GND")
	)
	(via
		(at 153.801105 100.3036)
		(size 0.4064)
		(drill 0.254)
		(layers "F.Cu" "B.Cu")
		(net "GND")
	)
	(via
		(at 157.468105 90.3156)
		(size 0.4064)
		(drill 0.254)
		(layers "F.Cu" "B.Cu")
		(net "GND")
	)
	(via
		(at 145.276105 87.2676)
		(size 0.4064)
		(drill 0.254)
		(layers "F.Cu" "B.Cu")
		(net "GND")
	)
	(via
		(at 146.801105 122.6036)
		(size 0.4064)
		(drill 0.254)
		(layers "F.Cu" "B.Cu")
		(net "GND")
	)
	(via
		(at 149.601105 98.14358)
		(size 0.4064)
		(drill 0.254)
		(layers "F.Cu" "B.Cu")
		(net "GND")
	)
	(via
		(at 142.806175 113.3307)
		(size 0.4064)
		(drill 0.254)
		(layers "F.Cu" "B.Cu")
		(net "GND")
	)
	(via
		(at 147.501105 104.50358)
		(size 0.4064)
		(drill 0.254)
		(layers "F.Cu" "B.Cu")
		(net "GND")
	)
	(via
		(at 145.401105 104.44357)
		(size 0.4064)
		(drill 0.254)
		(layers "F.Cu" "B.Cu")
		(net "GND")
	)
	(via
		(at 151.701105 102.34358)
		(size 0.4064)
		(drill 0.254)
		(layers "F.Cu" "B.Cu")
		(net "GND")
	)
	(via
		(at 144.260105 97.4276)
		(size 0.4064)
		(drill 0.254)
		(layers "F.Cu" "B.Cu")
		(net "GND")
	)
	(via
		(at 152.388105 91.3316)
		(size 0.4064)
		(drill 0.254)
		(layers "F.Cu" "B.Cu")
		(net "GND")
	)
	(via
		(at 149.801105 122.5036)
		(size 0.4064)
		(drill 0.254)
		(layers "F.Cu" "B.Cu")
		(net "GND")
	)
	(via
		(at 153.404105 90.3156)
		(size 0.4064)
		(drill 0.254)
		(layers "F.Cu" "B.Cu")
		(net "GND")
	)
	(via
		(at 155.683665 109.85944)
		(size 0.4064)
		(drill 0.254)
		(layers "F.Cu" "B.Cu")
		(net "GND")
	)
	(via
		(at 150.101105 116.0036)
		(size 0.4064)
		(drill 0.254)
		(layers "F.Cu" "B.Cu")
		(net "GND")
	)
	(via
		(at 147.901105 115.3036)
		(size 0.4064)
		(drill 0.254)
		(layers "F.Cu" "B.Cu")
		(net "GND")
	)
	(via
		(at 151.372105 86.2516)
		(size 0.4064)
		(drill 0.254)
		(layers "F.Cu" "B.Cu")
		(net "GND")
	)
	(via
		(at 143.301105 96.04359)
		(size 0.4064)
		(drill 0.254)
		(layers "F.Cu" "B.Cu")
		(net "GND")
	)
	(via
		(at 145.823925 109.79325)
		(size 0.4064)
		(drill 0.254)
		(layers "F.Cu" "B.Cu")
		(net "GND")
	)
	(via
		(at 156.452105 92.3476)
		(size 0.4064)
		(drill 0.254)
		(layers "F.Cu" "B.Cu")
		(net "GND")
	)
	(via
		(at 155.901105 100.30361)
		(size 0.4064)
		(drill 0.254)
		(layers "F.Cu" "B.Cu")
		(net "GND")
	)
	(via
		(at 155.901105 102.34358)
		(size 0.4064)
		(drill 0.254)
		(layers "F.Cu" "B.Cu")
		(net "GND")
	)
	(via
		(at 138.140655 121.80652)
		(size 0.4064)
		(drill 0.254)
		(layers "F.Cu" "B.Cu")
		(net "GND")
	)
	(via
		(at 141.201105 106.54357)
		(size 0.4064)
		(drill 0.254)
		(layers "F.Cu" "B.Cu")
		(net "GND")
	)
	(via
		(at 138.701105 119.5036)
		(size 0.4064)
		(drill 0.254)
		(layers "F.Cu" "B.Cu")
		(net "GND")
	)
	(via
		(at 155.436105 91.3316)
		(size 0.4064)
		(drill 0.254)
		(layers "F.Cu" "B.Cu")
		(net "GND")
	)
	(via
		(at 158.484105 92.3476)
		(size 0.4064)
		(drill 0.254)
		(layers "F.Cu" "B.Cu")
		(net "GND")
	)
	(via
		(at 141.201105 96.04359)
		(size 0.4064)
		(drill 0.254)
		(layers "F.Cu" "B.Cu")
		(net "GND")
	)
	(via
		(at 158.484105 87.2676)
		(size 0.4064)
		(drill 0.254)
		(layers "F.Cu" "B.Cu")
		(net "GND")
	)
	(via
		(at 138.701105 118.6036)
		(size 0.4064)
		(drill 0.254)
		(layers "F.Cu" "B.Cu")
		(net "GND")
	)
	(via
		(at 155.436105 90.3156)
		(size 0.4064)
		(drill 0.254)
		(layers "F.Cu" "B.Cu")
		(net "GND")
	)
	(via
		(at 152.701105 122.4036)
		(size 0.4064)
		(drill 0.254)
		(layers "F.Cu" "B.Cu")
		(net "GND")
	)
	(via
		(at 156.452105 90.3156)
		(size 0.4064)
		(drill 0.254)
		(layers "F.Cu" "B.Cu")
		(net "GND")
	)
	(via
		(at 156.555585 121.61008)
		(size 0.4064)
		(drill 0.254)
		(layers "F.Cu" "B.Cu")
		(net "GND")
	)
	(via
		(at 158.484105 88.2836)
		(size 0.4064)
		(drill 0.254)
		(layers "F.Cu" "B.Cu")
		(net "GND")
	)
	(via
		(at 156.452105 87.2676)
		(size 0.4064)
		(drill 0.254)
		(layers "F.Cu" "B.Cu")
		(net "GND")
	)
	(via
		(at 138.930175 85.01582)
		(size 0.4064)
		(drill 0.254)
		(layers "F.Cu" "B.Cu")
		(net "GND")
	)
	(via
		(at 147.501105 100.36361)
		(size 0.4064)
		(drill 0.254)
		(layers "F.Cu" "B.Cu")
		(net "GND")
	)
	(via
		(at 142.540665 88.25623)
		(size 0.4064)
		(drill 0.254)
		(layers "F.Cu" "B.Cu")
		(net "GND")
	)
	(via
		(at 141.201105 98.14358)
		(size 0.4064)
		(drill 0.254)
		(layers "F.Cu" "B.Cu")
		(net "GND")
	)
	(via
		(at 153.801105 106.54357)
		(size 0.4064)
		(drill 0.254)
		(layers "F.Cu" "B.Cu")
		(net "GND")
	)
	(via
		(at 153.404105 92.3476)
		(size 0.4064)
		(drill 0.254)
		(layers "F.Cu" "B.Cu")
		(net "GND")
	)
	(via
		(at 143.301105 100.3036)
		(size 0.4064)
		(drill 0.254)
		(layers "F.Cu" "B.Cu")
		(net "GND")
	)
	(via
		(at 152.388105 87.2676)
		(size 0.4064)
		(drill 0.254)
		(layers "F.Cu" "B.Cu")
		(net "GND")
	)
	(via
		(at 149.340105 87.2676)
		(size 0.4064)
		(drill 0.254)
		(layers "F.Cu" "B.Cu")
		(net "GND")
	)
	(via
		(at 146.292105 95.3956)
		(size 0.4064)
		(drill 0.254)
		(layers "F.Cu" "B.Cu")
		(net "GND")
	)
	(via
		(at 155.901105 106.54357)
		(size 0.4064)
		(drill 0.254)
		(layers "F.Cu" "B.Cu")
		(net "GND")
	)
	(via
		(at 151.372105 87.2676)
		(size 0.4064)
		(drill 0.254)
		(layers "F.Cu" "B.Cu")
		(net "GND")
	)
	(via
		(at 139.001105 120.97242)
		(size 0.4064)
		(drill 0.254)
		(layers "F.Cu" "B.Cu")
		(net "GND")
	)
	(via
		(at 158.201105 118.3036)
		(size 0.4064)
		(drill 0.254)
		(layers "F.Cu" "B.Cu")
		(net "GND")
	)
	(via
		(at 138.616245 85.82075)
		(size 0.4064)
		(drill 0.254)
		(layers "F.Cu" "B.Cu")
		(net "GND")
	)
	(via
		(at 156.452105 89.2996)
		(size 0.4064)
		(drill 0.254)
		(layers "F.Cu" "B.Cu")
		(net "GND")
	)
	(via
		(at 157.468105 93.3636)
		(size 0.4064)
		(drill 0.254)
		(layers "F.Cu" "B.Cu")
		(net "GND")
	)
	(via
		(at 158.484105 86.2516)
		(size 0.4064)
		(drill 0.254)
		(layers "F.Cu" "B.Cu")
		(net "GND")
	)
	(via
		(at 138.183655 120.97242)
		(size 0.4064)
		(drill 0.254)
		(layers "F.Cu" "B.Cu")
		(net "GND")
	)
	(via
		(at 157.468105 89.2996)
		(size 0.4064)
		(drill 0.254)
		(layers "F.Cu" "B.Cu")
		(net "GND")
	)
	(via
		(at 153.801105 104.44357)
		(size 0.4064)
		(drill 0.254)
		(layers "F.Cu" "B.Cu")
		(net "GND")
	)
	(via
		(at 138.780215 121.8036)
		(size 0.4064)
		(drill 0.254)
		(layers "F.Cu" "B.Cu")
		(net "GND")
	)
	(via
		(at 157.468105 92.3476)
		(size 0.4064)
		(drill 0.254)
		(layers "F.Cu" "B.Cu")
		(net "GND")
	)
	(via
		(at 145.401105 102.34358)
		(size 0.4064)
		(drill 0.254)
		(layers "F.Cu" "B.Cu")
		(net "GND")
	)
	(via
		(at 142.601105 88.9036)
		(size 0.4064)
		(drill 0.254)
		(layers "F.Cu" "B.Cu")
		(net "GND")
	)
	(via
		(at 149.601105 96.04359)
		(size 0.4064)
		(drill 0.254)
		(layers "F.Cu" "B.Cu")
		(net "GND")
	)
	(via
		(at 145.401105 100.3036)
		(size 0.4064)
		(drill 0.254)
		(layers "F.Cu" "B.Cu")
		(net "GND")
	)
	(via
		(at 153.801105 102.34358)
		(size 0.4064)
		(drill 0.254)
		(layers "F.Cu" "B.Cu")
		(net "GND")
	)
	(via
		(at 143.301105 102.34358)
		(size 0.4064)
		(drill 0.254)
		(layers "F.Cu" "B.Cu")
		(net "GND")
	)
	(via
		(at 150.356105 87.2676)
		(size 0.4064)
		(drill 0.254)
		(layers "F.Cu" "B.Cu")
		(net "GND")
	)
	(via
		(at 144.260105 95.3956)
		(size 0.4064)
		(drill 0.254)
		(layers "F.Cu" "B.Cu")
		(net "GND")
	)
	(via
		(at 157.468105 87.2676)
		(size 0.4064)
		(drill 0.254)
		(layers "F.Cu" "B.Cu")
		(net "GND")
	)
	(via
		(at 155.101105 121.6036)
		(size 0.4064)
		(drill 0.254)
		(layers "F.Cu" "B.Cu")
		(net "GND")
	)
	(via
		(at 143.301105 104.44357)
		(size 0.4064)
		(drill 0.254)
		(layers "F.Cu" "B.Cu")
		(net "GND")
	)
	(via
		(at 155.901105 104.44358)
		(size 0.4064)
		(drill 0.254)
		(layers "F.Cu" "B.Cu")
		(net "GND")
	)
	(via
		(at 151.701105 106.54357)
		(size 0.4064)
		(drill 0.254)
		(layers "F.Cu" "B.Cu")
		(net "GND")
	)
	(via
		(at 148.601105 122.5036)
		(size 0.4064)
		(drill 0.254)
		(layers "F.Cu" "B.Cu")
		(net "GND")
	)
	(via
		(at 153.404105 87.2676)
		(size 0.4064)
		(drill 0.254)
		(layers "F.Cu" "B.Cu")
		(net "GND")
	)
	(via
		(at 158.484105 85.2356)
		(size 0.4064)
		(drill 0.254)
		(layers "F.Cu" "B.Cu")
		(net "GND")
	)
	(via
		(at 158.484105 91.3316)
		(size 0.4064)
		(drill 0.254)
		(layers "F.Cu" "B.Cu")
		(net "GND")
	)
	(via
		(at 151.201105 122.4036)
		(size 0.4064)
		(drill 0.254)
		(layers "F.Cu" "B.Cu")
		(net "GND")
	)
	(via
		(at 149.601105 100.3036)
		(size 0.4064)
		(drill 0.254)
		(layers "F.Cu" "B.Cu")
		(net "GND")
	)
	(via
		(at 153.404105 88.2836)
		(size 0.4064)
		(drill 0.254)
		(layers "F.Cu" "B.Cu")
		(net "GND")
	)
	(via
		(at 147.501105 98.20359)
		(size 0.4064)
		(drill 0.254)
		(layers "F.Cu" "B.Cu")
		(net "GND")
	)
	(via
		(at 141.446295 112.93855)
		(size 0.4064)
		(drill 0.254)
		(layers "F.Cu" "B.Cu")
		(net "GND")
	)
	(via
		(at 155.436105 92.3476)
		(size 0.4064)
		(drill 0.254)
		(layers "F.Cu" "B.Cu")
		(net "GND")
	)
	(via
		(at 143.301105 106.54357)
		(size 0.4064)
		(drill 0.254)
		(layers "F.Cu" "B.Cu")
		(net "GND")
	)
	(via
		(at 149.601105 102.34358)
		(size 0.4064)
		(drill 0.254)
		(layers "F.Cu" "B.Cu")
		(net "GND")
	)
	(via
		(at 155.901105 98.14359)
		(size 0.4064)
		(drill 0.254)
		(layers "F.Cu" "B.Cu")
		(net "GND")
	)
	(via
		(at 144.260105 96.4116)
		(size 0.4064)
		(drill 0.254)
		(layers "F.Cu" "B.Cu")
		(net "GND")
	)
	(via
		(at 152.938435 115.40395)
		(size 0.4064)
		(drill 0.254)
		(layers "F.Cu" "B.Cu")
		(net "GND")
	)
	(via
		(at 144.260105 98.4436)
		(size 0.4064)
		(drill 0.254)
		(layers "F.Cu" "B.Cu")
		(net "GND")
	)
	(via
		(at 145.276105 85.2356)
		(size 0.4064)
		(drill 0.254)
		(layers "F.Cu" "B.Cu")
		(net "GND")
	)
	(via
		(at 157.301105 118.3036)
		(size 0.4064)
		(drill 0.254)
		(layers "F.Cu" "B.Cu")
		(net "GND")
	)
	(via
		(at 143.801105 122.2036)
		(size 0.4064)
		(drill 0.254)
		(layers "F.Cu" "B.Cu")
		(net "GND")
	)
	(via
		(at 153.801105 98.14358)
		(size 0.4064)
		(drill 0.254)
		(layers "F.Cu" "B.Cu")
		(net "GND")
	)
	(via
		(at 147.308105 87.2676)
		(size 0.4064)
		(drill 0.254)
		(layers "F.Cu" "B.Cu")
		(net "GND")
	)
	(via
		(at 148.501105 84.00359)
		(size 5.5)
		(drill 3.5)
		(layers "F.Cu" "B.Cu")
		(padstack
			(mode front_inner_back)
			(layer "Inner"
				(size 5.5)
			)
			(layer "B.Cu"
				(size 6)
			)
		)
		(net "GND")
	)
	(via
		(at 152.003765 111.48561)
		(size 0.4064)
		(drill 0.254)
		(layers "F.Cu" "B.Cu")
		(net "GND")
	)
	(via
		(at 143.301105 98.14358)
		(size 0.4064)
		(drill 0.254)
		(layers "F.Cu" "B.Cu")
		(net "GND")
	)
	(via
		(at 151.327285 109.79325)
		(size 0.4064)
		(drill 0.254)
		(layers "F.Cu" "B.Cu")
		(net "GND")
	)
	(via
		(at 155.901105 96.04359)
		(size 0.4064)
		(drill 0.254)
		(layers "F.Cu" "B.Cu")
		(net "GND")
	)
	(via
		(at 145.401105 96.04359)
		(size 0.4064)
		(drill 0.254)
		(layers "F.Cu" "B.Cu")
		(net "GND")
	)
	(via
		(at 144.260105 86.2516)
		(size 0.4064)
		(drill 0.254)
		(layers "F.Cu" "B.Cu")
		(net "GND")
	)
	(via
		(at 149.601105 104.44357)
		(size 0.4064)
		(drill 0.254)
		(layers "F.Cu" "B.Cu")
		(net "GND")
	)
	(via
		(at 151.701105 96.04359)
		(size 0.4064)
		(drill 0.254)
		(layers "F.Cu" "B.Cu")
		(net "GND")
	)
	(via
		(at 157.468105 91.3316)
		(size 0.4064)
		(drill 0.254)
		(layers "F.Cu" "B.Cu")
		(net "GND")
	)
	(via
		(at 141.201105 102.34358)
		(size 0.4064)
		(drill 0.254)
		(layers "F.Cu" "B.Cu")
		(net "GND")
	)
	(via
		(at 151.701105 98.14358)
		(size 0.4064)
		(drill 0.254)
		(layers "F.Cu" "B.Cu")
		(net "GND")
	)
	(segment
		(start 142.711305 112.05938)
		(end 142.711305 112.0036)
		(width 0.3048)
		(layer "F.Cu")
		(net "+3V3")
	)
	(segment
		(start 142.648715 91.7536)
		(end 143.010345 91.7536)
		(width 0.254)
		(layer "F.Cu")
		(net "+3V3")
	)
	(segment
		(start 142.711305 112.0036)
		(end 143.401105 112.0036)
		(width 0.3048)
		(layer "F.Cu")
		(net "+3V3")
	)
	(segment
		(start 148.118865 111.3036)
		(end 148.122545 111.29992)
		(width 0.508)
		(layer "F.Cu")
		(net "+3V3")
	)
	(segment
		(start 146.684155 111.31522)
		(end 146.684155 110.48324)
		(width 0.508)
		(layer "F.Cu")
		(net "+3V3")
	)
	(segment
		(start 146.901105 110.24774)
		(end 146.901105 108.74359)
		(width 0.508)
		(layer "F.Cu")
		(net "+3V3")
	)
	(segment
		(start 142.901105 90.76914)
		(end 143.010345 90.87837)
		(width 0.254)
		(layer "F.Cu")
		(net "+3V3")
	)
	(segment
		(start 141.483455 89.81808)
		(end 141.501105 89.83573)
		(width 0.254)
		(layer "F.Cu")
		(net "+3V3")
	)
	(segment
		(start 140.788955 114.27079)
		(end 141.680315 114.27079)
		(width 0.3048)
		(layer "F.Cu")
		(net "+3V3")
	)
	(segment
		(start 143.010345 91.7536)
		(end 143.010345 90.87837)
		(width 0.254)
		(layer "F.Cu")
		(net "+3V3")
	)
	(segment
		(start 148.001105 108.74359)
		(end 148.118865 108.86136)
		(width 0.508)
		(layer "F.Cu")
		(net "+3V3")
	)
	(segment
		(start 140.642485 85.68518)
		(end 140.642485 85.01642)
		(width 0.1905)
		(layer "F.Cu")
		(net "+3V3")
	)
	(segment
		(start 141.454295 89.84724)
		(end 141.483455 89.81808)
		(width 0.254)
		(layer "F.Cu")
		(net "+3V3")
	)
	(segment
		(start 141.501105 90.57504)
		(end 141.501105 89.83573)
		(width 0.254)
		(layer "F.Cu")
		(net "+3V3")
	)
	(segment
		(start 148.122545 111.29992)
		(end 148.122545 110.5036)
		(width 0.508)
		(layer "F.Cu")
		(net "+3V3")
	)
	(segment
		(start 142.492625 91.86845)
		(end 142.533865 91.86845)
		(width 0.254)
		(layer "F.Cu")
		(net "+3V3")
	)
	(segment
		(start 140.351105 89.87024)
		(end 140.374105 89.84724)
		(width 0.254)
		(layer "F.Cu")
		(net "+3V3")
	)
	(segment
		(start 148.118865 110.49993)
		(end 148.118865 108.86136)
		(width 0.508)
		(layer "F.Cu")
		(net "+3V3")
	)
	(segment
		(start 142.533865 91.86845)
		(end 142.648715 91.7536)
		(width 0.254)
		(layer "F.Cu")
		(net "+3V3")
	)
	(segment
		(start 146.681925 110.481)
		(end 146.684155 110.48324)
		(width 0.508)
		(layer "F.Cu")
		(net "+3V3")
	)
	(segment
		(start 150.201105 112.08216)
		(end 150.322545 112.2036)
		(width 0.508)
		(layer "F.Cu")
		(net "+3V3")
	)
	(segment
		(start 140.704665 85.0786)
		(end 141.951105 85.0786)
		(width 0.1905)
		(layer "F.Cu")
		(net "+3V3")
	)
	(segment
		(start 140.351105 90.0036)
		(end 140.351105 89.87024)
		(width 0.254)
		(layer "F.Cu")
		(net "+3V3")
	)
	(segment
		(start 141.680315 114.27944)
		(end 141.680315 114.27079)
		(width 0.3048)
		(layer "F.Cu")
		(net "+3V3")
	)
	(segment
		(start 143.010345 91.7536)
		(end 144.101105 91.7536)
		(width 0.254)
		(layer "F.Cu")
		(net "+3V3")
	)
	(segment
		(start 140.642485 85.01642)
		(end 140.704665 85.0786)
		(width 0.1905)
		(layer "F.Cu")
		(net "+3V3")
	)
	(segment
		(start 150.201105 112.08216)
		(end 150.201105 108.74359)
		(width 0.508)
		(layer "F.Cu")
		(net "+3V3")
	)
	(segment
		(start 138.601105 92.1036)
		(end 140.101105 92.1036)
		(width 0.1905)
		(layer "F.Cu")
		(net "+3V3")
	)
	(segment
		(start 140.374105 89.84724)
		(end 141.454295 89.84724)
		(width 0.254)
		(layer "F.Cu")
		(net "+3V3")
	)
	(segment
		(start 140.629665 85.0036)
		(end 140.642485 85.01642)
		(width 0.1905)
		(layer "F.Cu")
		(net "+3V3")
	)
	(segment
		(start 148.118865 110.49993)
		(end 148.122545 110.5036)
		(width 0.508)
		(layer "F.Cu")
		(net "+3V3")
	)
	(via
		(at 140.801105 120.83908)
		(size 0.4064)
		(drill 0.254)
		(layers "F.Cu" "B.Cu")
		(net "+3V3")
	)
	(via
		(at 157.901105 121.99824)
		(size 0.4064)
		(drill 0.254)
		(layers "F.Cu" "B.Cu")
		(net "+3V3")
	)
	(via
		(at 148.118865 111.3036)
		(size 0.4064)
		(drill 0.254)
		(layers "F.Cu" "B.Cu")
		(net "+3V3")
	)
	(via
		(at 146.684155 111.31522)
		(size 0.4064)
		(drill 0.254)
		(layers "F.Cu" "B.Cu")
		(net "+3V3")
	)
	(via
		(at 141.483455 89.81808)
		(size 0.4064)
		(drill 0.254)
		(layers "F.Cu" "B.Cu")
		(net "+3V3")
	)
	(via
		(at 157.201105 120.8036)
		(size 0.4064)
		(drill 0.254)
		(layers "F.Cu" "B.Cu")
		(net "+3V3")
	)
	(via
		(at 138.601105 92.1036)
		(size 0.4064)
		(drill 0.254)
		(layers "F.Cu" "B.Cu")
		(net "+3V3")
	)
	(via
		(at 140.801105 122.2036)
		(size 0.4064)
		(drill 0.254)
		(layers "F.Cu" "B.Cu")
		(net "+3V3")
	)
	(via
		(at 158.101105 120.8036)
		(size 0.4064)
		(drill 0.254)
		(layers "F.Cu" "B.Cu")
		(net "+3V3")
	)
	(via
		(at 140.642485 85.68518)
		(size 0.4064)
		(drill 0.254)
		(layers "F.Cu" "B.Cu")
		(net "+3V3")
	)
	(via
		(at 141.276885 118.7036)
		(size 0.4064)
		(drill 0.254)
		(layers "F.Cu" "B.Cu")
		(net "+3V3")
	)
	(via
		(at 140.801105 122.9036)
		(size 0.4064)
		(drill 0.254)
		(layers "F.Cu" "B.Cu")
		(net "+3V3")
	)
	(via
		(at 158.616675 122.14162)
		(size 0.4064)
		(drill 0.254)
		(layers "F.Cu" "B.Cu")
		(net "+3V3")
	)
	(via
		(at 142.492625 91.86845)
		(size 0.4064)
		(drill 0.254)
		(layers "F.Cu" "B.Cu")
		(net "+3V3")
	)
	(via
		(at 140.789115 121.48701)
		(size 0.4064)
		(drill 0.254)
		(layers "F.Cu" "B.Cu")
		(net "+3V3")
	)
	(via
		(at 150.322545 112.2036)
		(size 0.4064)
		(drill 0.254)
		(layers "F.Cu" "B.Cu")
		(net "+3V3")
	)
	(via
		(at 141.680315 114.27944)
		(size 0.4064)
		(drill 0.254)
		(layers "F.Cu" "B.Cu")
		(net "+3V3")
	)
	(via
		(at 141.201105 119.6036)
		(size 0.4064)
		(drill 0.254)
		(layers "F.Cu" "B.Cu")
		(net "+3V3")
	)
	(via
		(at 142.711305 112.05938)
		(size 0.4064)
		(drill 0.254)
		(layers "F.Cu" "B.Cu")
		(net "+3V3")
	)
	(segment
		(start 157.507105 124.4786)
		(end 157.507105 122.9976)
		(width 0.3048)
		(layer "B.Cu")
		(net "+3V3")
	)
	(segment
		(start 140.507105 124.4786)
		(end 140.507105 122.8234)
		(width 0.254)
		(layer "B.Cu")
		(net "+3V3")
	)
	(segment
		(start 157.846065 122.65864)
		(end 158.099645 122.65864)
		(width 0.3048)
		(layer "B.Cu")
		(net "+3V3")
	)
	(segment
		(start 139.507105 124.4786)
		(end 139.507105 123.0036)
		(width 0.254)
		(layer "B.Cu")
		(net "+3V3")
	)
	(segment
		(start 157.007105 124.4786)
		(end 157.007105 122.89224)
		(width 0.3048)
		(layer "B.Cu")
		(net "+3V3")
	)
	(segment
		(start 157.007105 122.89224)
		(end 157.901105 121.99824)
		(width 0.3048)
		(layer "B.Cu")
		(net "+3V3")
	)
	(segment
		(start 158.099645 122.65864)
		(end 158.616675 122.14162)
		(width 0.3048)
		(layer "B.Cu")
		(net "+3V3")
	)
	(segment
		(start 157.507105 122.9976)
		(end 157.846065 122.65864)
		(width 0.3048)
		(layer "B.Cu")
		(net "+3V3")
	)
	(segment
		(start 140.007105 124.4786)
		(end 140.007105 122.80092)
		(width 0.254)
		(layer "B.Cu")
		(net "+3V3")
	)
	(zone
		(layer "F.Cu")
		(hatch edge 0.5)
		(connect_pads
			(clearance 0)
		)
		(min_thickness 0.25)
		(keepout
			(tracks allowed)
			(vias allowed)
			(pads allowed)
			(copperpour not_allowed)
			(footprints allowed)
		)
		(placement
			(enabled no)
			(sheetname "")
		)
		(fill
			(thermal_gap 0.5)
			(thermal_bridge_width 0.5)
			(island_removal_mode 0)
		)
		(polygon
			(pts
				(xy 146.901105 88.1036) (xy 146.901105 90.96334) (xy 152.051105 90.96334) (xy 152.051105 87.99262)
				(xy 146.951105 87.99262)
			)
		)
	)
	(zone
		(net "GND")
		(layer "F.Cu")
		(hatch edge 0.5)
		(priority 6)
		(connect_pads yes
			(clearance 0.5)
		)
		(min_thickness 0.25)
		(fill yes
			(thermal_gap 0.254)
			(thermal_bridge_width 0.508)
			(island_removal_mode 0)
		)
		(polygon
			(pts
				(xy 137.501085 84.00359) (xy 159.501115 84.00359) (xy 159.501115 122.8536) (xy 137.501095 122.8536)
			)
		)
	)
	(zone
		(layers "F.Cu" "B.Cu" "In1.Cu" "In2.Cu")
		(hatch edge 0.5)
		(connect_pads
			(clearance 0)
		)
		(min_thickness 0.25)
		(keepout
			(tracks not_allowed)
			(vias not_allowed)
			(pads not_allowed)
			(copperpour not_allowed)
			(footprints allowed)
		)
		(placement
			(enabled no)
			(sheetname "")
		)
		(fill
			(thermal_gap 0.5)
			(thermal_bridge_width 0.5)
			(island_removal_mode 0)
		)
		(polygon
			(pts
				(xy 198.940755 161.0886) (xy 198.941968 161.084868) (xy 198.945143 161.082561) (xy 198.949067 161.082561)
				(xy 198.952242 161.084868) (xy 198.953455 161.0886) (xy 198.937897 161.26654) (xy 198.891696 161.43908)
				(xy 198.816252 161.600984) (xy 198.713857 161.74734) (xy 198.587616 161.873704) (xy 198.441362 161.976244)
				(xy 198.279532 162.051846) (xy 198.107037 162.098217) (xy 197.929112 162.11395) (xy 197.925379 162.112741)
				(xy 197.923069 162.109568) (xy 197.923065 162.105644) (xy 197.925369 162.102466) (xy 197.9291 162.10125)
				(xy 198.01764 162.101168) (xy 198.192003 162.070266) (xy 198.358358 162.009574) (xy 198.511656 161.920933)
				(xy 198.647245 161.807034) (xy 198.761011 161.671333) (xy 198.849501 161.517948) (xy 198.910029 161.351534)
				(xy 198.94076 161.17714) (xy 198.940755 161.0886)
			)
		)
	)
	(zone
		(net "+3V3")
		(layer "B.Cu")
		(hatch edge 0.5)
		(priority 4)
		(connect_pads yes
			(clearance 0.5)
		)
		(min_thickness 0.25)
		(fill yes
			(thermal_gap 0.254)
			(thermal_bridge_width 0.508)
			(island_removal_mode 0)
		)
		(polygon
			(pts
				(xy 159.001105 120.4734) (xy 159.001105 122.4036) (xy 158.201105 122.6036) (xy 158.001105 122.9036)
				(xy 156.866785 122.9036) (xy 156.866785 120.4734)
			)
		)
	)
	(zone
		(net "+3V3")
		(layer "B.Cu")
		(hatch edge 0.5)
		(priority 10)
		(connect_pads yes
			(clearance 0.5)
		)
		(min_thickness 0.25)
		(fill yes
			(thermal_gap 0.254)
			(thermal_bridge_width 0.508)
			(island_removal_mode 0)
		)
		(polygon
			(pts
				(xy 139.332105 120.4036) (xy 139.332105 123.2036) (xy 141.507105 123.2036) (xy 141.507105 120.4036)
				(xy 141.101105 120.4036)
			)
		)
	)
	(zone
		(net "GND")
		(layer "B.Cu")
		(hatch edge 0.5)
		(priority 3)
		(connect_pads yes
			(clearance 0.5)
		)
		(min_thickness 0.25)
		(fill yes
			(thermal_gap 0.254)
			(thermal_bridge_width 0.508)
			(island_removal_mode 0)
		)
		(polygon
			(pts
				(xy 137.501085 84.00359) (xy 137.501085 122.56433) (xy 159.501115 122.56433) (xy 159.501115 84.00359)
				(xy 156.631105 84.00359)
			)
		)
	)
	(zone
		(net "GND")
		(layer "In1.Cu")
		(hatch edge 0.5)
		(priority 2)
		(connect_pads yes
			(clearance 0.5)
		)
		(min_thickness 0.25)
		(fill yes
			(thermal_gap 0.254)
			(thermal_bridge_width 0.508)
			(island_removal_mode 0)
		)
		(polygon
			(pts
				(xy 137.590815 84.00359) (xy 159.501115 84.00359) (xy 159.501115 123.1036) (xy 137.401105 123.1036)
				(xy 137.401105 122.7036)
			)
		)
	)
	(zone
		(net "+3V3")
		(layer "In2.Cu")
		(hatch edge 0.5)
		(priority 1)
		(connect_pads yes
			(clearance 0.5)
		)
		(min_thickness 0.25)
		(fill yes
			(thermal_gap 0.254)
			(thermal_bridge_width 0.508)
			(island_removal_mode 0)
		)
		(polygon
			(pts
				(xy 143.801105 98.95985) (xy 159.501115 98.95985) (xy 159.501115 123.1036) (xy 137.501095 123.1036)
				(xy 137.501095 84.00359) (xy 143.801105 84.00359) (xy 143.801105 84.7036)
			)
		)
	)
	(zone
		(net "GND")
		(layer "In2.Cu")
		(hatch edge 0.5)
		(connect_pads yes
			(clearance 0.5)
		)
		(min_thickness 0.25)
		(fill yes
			(thermal_gap 0.254)
			(thermal_bridge_width 0.508)
			(island_removal_mode 0)
		)
		(polygon
			(pts
				(xy 142.901105 84.1036) (xy 142.901105 99.6036) (xy 160.601105 99.6036) (xy 160.601105 84.1036)
			)
		)
	)
)
